FILE_TYPE = MACRO_DRAWING;
SET COLOR_WIRE YELLOW;
SET COLOR_PROP MONO;
SET COLOR_DOT WHITE;
SET COLOR_ARC YELLOW;
SET COLOR_BODY GREEN;
SET COLOR_NOTE MONO;
SET PROP_DISPLAY VALUE;
SET PAGE_NUMBER P151;
FORCEADD GND..1
(-7325 125);
FORCEPROP 3 LASTPIN (-7325 175) SIG_NAME GND\g
J 0
(-7315 185);
DISPLAY 0.659574 (-7315 185);
PAINT MONO (-7315 185);
DISPLAY INVISIBLE (-7315 185);
FORCEPROP 1 LAST PATH I1
J 0
(-7250 125);
DISPLAY 0.872340 (-7250 125);
PAINT AQUA (-7250 125);
DISPLAY INVISIBLE (-7250 125);
FORCEPROP 1 LAST VOLTAGE 0.0V
J 0
(-7370 82);
DISPLAY 0.340426 (-7370 82);
PAINT GREEN (-7370 82);
DISPLAY INVISIBLE (-7370 82);
FORCEPROP 1 LAST SIZE 1B
J 0
(-7250 75);
DISPLAY 0.872340 (-7250 75);
PAINT AQUA (-7250 75);
DISPLAY INVISIBLE (-7250 75);
FORCEPROP 2 LAST CDS_LIB mstr_symbols
J 0
(-7325 125);
PAINT MONO (-7325 125);
DISPLAY INVISIBLE (-7325 125);
FORCEPROP 1 LAST BODY_TYPE PLUMBING
J 0
(-7370 82);
DISPLAY 0.340426 (-7370 82);
PAINT GREEN (-7370 82);
DISPLAY INVISIBLE (-7370 82);
FORCEPROP 1 LAST HDL_POWER GND
J 0
(-7325 275);
DISPLAY 0.872340 (-7325 275);
PAINT GREEN (-7325 275);
DISPLAY INVISIBLE (-7325 275);
FORCEADD RES..1
(-6900 4425);
FORCEPROP 1 LAST MATERIAL CHIP
J 0
(-6750 4375);
DISPLAY 0.617021 (-6750 4375);
PAINT SKYBLUE (-6750 4375);
FORCEPROP 1 LAST TOLERANCE 1%
J 0
(-6825 4375);
DISPLAY 0.617021 (-6825 4375);
PAINT SKYBLUE (-6825 4375);
FORCEPROP 1 LAST VALUE 4.75K
J 2
(-6750 4450);
DISPLAY 0.617021 (-6750 4450);
PAINT SKYBLUE (-6750 4450);
FORCEPROP 1 LAST LOCATION R25W96
J 0
(-6950 4475);
DISPLAY 0.617021 (-6950 4475);
PAINT AQUA (-6950 4475);
FORCEPROP 1 LAST PART_NUMBER G21796-072
J 0
(-6725 4450);
DISPLAY 0.617021 (-6725 4450);
PAINT BLUE (-6725 4450);
FORCEPROP 1 LAST WATTAGE 1/16W
J 2
(-6975 4375);
DISPLAY 0.617021 (-6975 4375);
PAINT SKYBLUE (-6975 4375);
FORCEPROP 1 LAST PACK_TYPE 0402
J 0
(-7075 4450);
DISPLAY 0.617021 (-7075 4450);
PAINT SKYBLUE (-7075 4450);
FORCEPROP 1 LAST PATH I10
J 0
(-6950 4575);
DISPLAY 0.978723 (-6950 4575);
PAINT WHITE (-6950 4575);
DISPLAY INVISIBLE (-6950 4575);
FORCEPROP 2 LAST CDS_LIB mstr_discrete
J 0
(-6900 4425);
PAINT MONO (-6900 4425);
DISPLAY INVISIBLE (-6900 4425);
FORCEPROP 2 LAST BOM_COST SM_CONTROLLER
J 0
(-6950 4575);
DISPLAY 1.021277 (-6950 4575);
PAINT ORANGE (-6950 4575);
DISPLAY INVISIBLE (-6950 4575);
FORCEPROP 2 LAST ROOM BMC
J 0
(-6950 4525);
DISPLAY 1.021277 (-6950 4525);
PAINT ORANGE (-6950 4525);
DISPLAY INVISIBLE (-6950 4525);
FORCEPROP 1 LASTPIN (-7000 4425) $PN 1
J 0
(-6988 4437);
DISPLAY 0.787234 (-6988 4437);
PAINT ORANGE (-6988 4437);
DISPLAY INVISIBLE (-6988 4437);
FORCEPROP 1 LASTPIN (-6800 4425) $PN 2
J 0
(-6838 4437);
DISPLAY 0.787234 (-6838 4437);
PAINT ORANGE (-6838 4437);
DISPLAY INVISIBLE (-6838 4437);
FORCEADD RES..1
(-6900 4275);
FORCEPROP 1 LAST LOCATION R25W97
J 0
(-6950 4325);
DISPLAY 0.617021 (-6950 4325);
PAINT AQUA (-6950 4325);
FORCEPROP 1 LAST PACK_TYPE 0402
J 0
(-7075 4300);
DISPLAY 0.617021 (-7075 4300);
PAINT SKYBLUE (-7075 4300);
FORCEPROP 1 LAST VALUE 4.75K
J 2
(-6750 4300);
DISPLAY 0.617021 (-6750 4300);
PAINT SKYBLUE (-6750 4300);
FORCEPROP 1 LAST TOLERANCE 1%
J 0
(-6825 4225);
DISPLAY 0.617021 (-6825 4225);
PAINT SKYBLUE (-6825 4225);
FORCEPROP 1 LAST PART_NUMBER G21796-072
J 0
(-6725 4300);
DISPLAY 0.617021 (-6725 4300);
PAINT BLUE (-6725 4300);
FORCEPROP 1 LAST MATERIAL EMPTY
J 0
(-6750 4225);
DISPLAY 0.617021 (-6750 4225);
PAINT RED (-6750 4225);
FORCEPROP 1 LAST WATTAGE 1/16W
J 2
(-6975 4225);
DISPLAY 0.617021 (-6975 4225);
PAINT SKYBLUE (-6975 4225);
FORCEPROP 1 LAST PATH I11
J 0
(-6950 4425);
DISPLAY 0.978723 (-6950 4425);
PAINT WHITE (-6950 4425);
DISPLAY INVISIBLE (-6950 4425);
FORCEPROP 1 LASTPIN (-7000 4275) $PN 1
J 0
(-6988 4287);
DISPLAY 0.787234 (-6988 4287);
PAINT ORANGE (-6988 4287);
DISPLAY INVISIBLE (-6988 4287);
FORCEPROP 2 LAST CDS_LIB mstr_discrete
J 0
(-6900 4275);
PAINT ORANGE (-6900 4275);
DISPLAY INVISIBLE (-6900 4275);
FORCEPROP 2 LAST ROOM BMC
J 0
(-6950 4375);
DISPLAY 1.021277 (-6950 4375);
PAINT ORANGE (-6950 4375);
DISPLAY INVISIBLE (-6950 4375);
FORCEPROP 1 LASTPIN (-6800 4275) $PN 2
J 0
(-6838 4287);
DISPLAY 0.787234 (-6838 4287);
PAINT ORANGE (-6838 4287);
DISPLAY INVISIBLE (-6838 4287);
FORCEPROP 2 LAST $SEC 1
J 0
(-6950 4475);
PAINT MONO (-6950 4475);
DISPLAY INVISIBLE (-6950 4475);
FORCEPROP 2 LAST CDS_SEC 1
J 0
(-6950 4475);
PAINT MONO (-6950 4475);
DISPLAY INVISIBLE (-6950 4475);
FORCEPROP 2 LAST BOM_COST SM_CONTROLLER
J 0
(-6950 4425);
DISPLAY 1.021277 (-6950 4425);
PAINT ORANGE (-6950 4425);
DISPLAY INVISIBLE (-6950 4425);
FORCEPROP 2 LAST CDS_LOCATION R25W97
J 0
(-6950 4325);
DISPLAY 0.617021 (-6950 4325);
PAINT AQUA (-6950 4325);
DISPLAY INVISIBLE (-6950 4325);
FORCEADD RES..1
(-6900 4000);
FORCEPROP 1 LAST LOCATION R25W98
J 0
(-6950 4050);
DISPLAY 0.617021 (-6950 4050);
PAINT AQUA (-6950 4050);
FORCEPROP 1 LAST PART_NUMBER G21796-072
J 0
(-6725 4025);
DISPLAY 0.617021 (-6725 4025);
PAINT BLUE (-6725 4025);
FORCEPROP 1 LAST MATERIAL CHIP
J 0
(-6750 3950);
DISPLAY 0.617021 (-6750 3950);
PAINT SKYBLUE (-6750 3950);
FORCEPROP 1 LAST TOLERANCE 1%
J 0
(-6825 3950);
DISPLAY 0.617021 (-6825 3950);
PAINT SKYBLUE (-6825 3950);
FORCEPROP 1 LAST VALUE 4.75K
J 2
(-6750 4025);
DISPLAY 0.617021 (-6750 4025);
PAINT SKYBLUE (-6750 4025);
FORCEPROP 1 LAST WATTAGE 1/16W
J 2
(-6975 3950);
DISPLAY 0.617021 (-6975 3950);
PAINT SKYBLUE (-6975 3950);
FORCEPROP 1 LAST PACK_TYPE 0402
J 0
(-7075 4025);
DISPLAY 0.617021 (-7075 4025);
PAINT SKYBLUE (-7075 4025);
FORCEPROP 1 LAST PATH I12
J 0
(-6950 4150);
DISPLAY 0.978723 (-6950 4150);
PAINT WHITE (-6950 4150);
DISPLAY INVISIBLE (-6950 4150);
FORCEPROP 2 LAST CDS_LIB mstr_discrete
J 0
(-6900 4000);
PAINT MONO (-6900 4000);
DISPLAY INVISIBLE (-6900 4000);
FORCEPROP 2 LAST BOM_COST SM_CONTROLLER
J 0
(-6950 4150);
DISPLAY 1.021277 (-6950 4150);
PAINT ORANGE (-6950 4150);
DISPLAY INVISIBLE (-6950 4150);
FORCEPROP 2 LAST ROOM BMC
J 0
(-6950 4100);
DISPLAY 1.021277 (-6950 4100);
PAINT ORANGE (-6950 4100);
DISPLAY INVISIBLE (-6950 4100);
FORCEPROP 1 LASTPIN (-7000 4000) $PN 1
J 0
(-6988 4012);
DISPLAY 0.787234 (-6988 4012);
PAINT ORANGE (-6988 4012);
DISPLAY INVISIBLE (-6988 4012);
FORCEPROP 1 LASTPIN (-6800 4000) $PN 2
J 0
(-6838 4012);
DISPLAY 0.787234 (-6838 4012);
PAINT ORANGE (-6838 4012);
DISPLAY INVISIBLE (-6838 4012);
FORCEADD RES..1
(-6900 3625);
FORCEPROP 1 LAST PART_NUMBER G21796-072
J 0
(-6725 3650);
DISPLAY 0.617021 (-6725 3650);
PAINT BLUE (-6725 3650);
FORCEPROP 1 LAST MATERIAL CHIP
J 0
(-6750 3575);
DISPLAY 0.617021 (-6750 3575);
PAINT SKYBLUE (-6750 3575);
FORCEPROP 1 LAST TOLERANCE 1%
J 0
(-6825 3575);
DISPLAY 0.617021 (-6825 3575);
PAINT SKYBLUE (-6825 3575);
FORCEPROP 1 LAST WATTAGE 1/16W
J 2
(-6975 3575);
DISPLAY 0.617021 (-6975 3575);
PAINT SKYBLUE (-6975 3575);
FORCEPROP 1 LAST LOCATION R25W100
J 0
(-6950 3675);
DISPLAY 0.617021 (-6950 3675);
PAINT AQUA (-6950 3675);
FORCEPROP 1 LAST PACK_TYPE 0402
J 0
(-7075 3650);
DISPLAY 0.617021 (-7075 3650);
PAINT SKYBLUE (-7075 3650);
FORCEPROP 1 LAST VALUE 4.75K
J 2
(-6750 3650);
DISPLAY 0.617021 (-6750 3650);
PAINT SKYBLUE (-6750 3650);
FORCEPROP 1 LAST PATH I13
J 0
(-6950 3775);
DISPLAY 0.978723 (-6950 3775);
PAINT WHITE (-6950 3775);
DISPLAY INVISIBLE (-6950 3775);
FORCEPROP 2 LAST ROOM BMC
J 0
(-6950 3725);
DISPLAY 1.021277 (-6950 3725);
PAINT ORANGE (-6950 3725);
DISPLAY INVISIBLE (-6950 3725);
FORCEPROP 2 LAST BOM_COST SM_CONTROLLER
J 0
(-6950 3775);
DISPLAY 1.021277 (-6950 3775);
PAINT ORANGE (-6950 3775);
DISPLAY INVISIBLE (-6950 3775);
FORCEPROP 2 LAST CDS_LIB mstr_discrete
J 0
(-6900 3625);
PAINT MONO (-6900 3625);
DISPLAY INVISIBLE (-6900 3625);
FORCEPROP 1 LASTPIN (-7000 3625) $PN 1
J 0
(-6988 3637);
DISPLAY 0.787234 (-6988 3637);
PAINT ORANGE (-6988 3637);
DISPLAY INVISIBLE (-6988 3637);
FORCEPROP 1 LASTPIN (-6800 3625) $PN 2
J 0
(-6838 3637);
DISPLAY 0.787234 (-6838 3637);
PAINT ORANGE (-6838 3637);
DISPLAY INVISIBLE (-6838 3637);
FORCEADD RES..1
(-6925 3825);
FORCEPROP 1 LAST MATERIAL EMPTY
J 0
(-6775 3775);
DISPLAY 0.617021 (-6775 3775);
PAINT RED (-6775 3775);
FORCEPROP 1 LAST WATTAGE 1/16W
J 2
(-7000 3775);
DISPLAY 0.617021 (-7000 3775);
PAINT SKYBLUE (-7000 3775);
FORCEPROP 1 LAST TOLERANCE 1%
J 0
(-6850 3775);
DISPLAY 0.617021 (-6850 3775);
PAINT SKYBLUE (-6850 3775);
FORCEPROP 1 LAST LOCATION R25W99
J 0
(-6975 3875);
DISPLAY 0.617021 (-6975 3875);
PAINT AQUA (-6975 3875);
FORCEPROP 1 LAST PACK_TYPE 0402
J 0
(-7100 3850);
DISPLAY 0.617021 (-7100 3850);
PAINT SKYBLUE (-7100 3850);
FORCEPROP 1 LAST VALUE 4.75K
J 2
(-6775 3850);
DISPLAY 0.617021 (-6775 3850);
PAINT SKYBLUE (-6775 3850);
FORCEPROP 1 LAST PART_NUMBER G21796-072
J 0
(-6750 3850);
DISPLAY 0.617021 (-6750 3850);
PAINT BLUE (-6750 3850);
FORCEPROP 1 LAST PATH I14
J 0
(-6975 3975);
DISPLAY 0.978723 (-6975 3975);
PAINT WHITE (-6975 3975);
DISPLAY INVISIBLE (-6975 3975);
FORCEPROP 1 LASTPIN (-7025 3825) $PN 1
J 0
(-7013 3837);
DISPLAY 0.787234 (-7013 3837);
PAINT ORANGE (-7013 3837);
DISPLAY INVISIBLE (-7013 3837);
FORCEPROP 2 LAST CDS_LIB mstr_discrete
J 0
(-6925 3825);
PAINT ORANGE (-6925 3825);
DISPLAY INVISIBLE (-6925 3825);
FORCEPROP 2 LAST ROOM BMC
J 0
(-6975 3925);
DISPLAY 1.021277 (-6975 3925);
PAINT ORANGE (-6975 3925);
DISPLAY INVISIBLE (-6975 3925);
FORCEPROP 1 LASTPIN (-6825 3825) $PN 2
J 0
(-6863 3837);
DISPLAY 0.787234 (-6863 3837);
PAINT ORANGE (-6863 3837);
DISPLAY INVISIBLE (-6863 3837);
FORCEPROP 2 LAST $SEC 1
J 0
(-6975 4025);
PAINT MONO (-6975 4025);
DISPLAY INVISIBLE (-6975 4025);
FORCEPROP 2 LAST CDS_SEC 1
J 0
(-6975 4025);
PAINT MONO (-6975 4025);
DISPLAY INVISIBLE (-6975 4025);
FORCEPROP 2 LAST BOM_COST SM_CONTROLLER
J 0
(-6975 3975);
DISPLAY 1.021277 (-6975 3975);
PAINT ORANGE (-6975 3975);
DISPLAY INVISIBLE (-6975 3975);
FORCEPROP 2 LAST CDS_LOCATION R25W99
J 0
(-6975 3875);
DISPLAY 0.617021 (-6975 3875);
PAINT AQUA (-6975 3875);
DISPLAY INVISIBLE (-6975 3875);
FORCEADD P3V3_STBY..1
(-7325 4850);
FORCEPROP 3 LASTPIN (-7325 4800) SIG_NAME P3V3_STBY\g
J 0
(-7315 4810);
DISPLAY 0.659574 (-7315 4810);
PAINT MONO (-7315 4810);
DISPLAY INVISIBLE (-7315 4810);
FORCEPROP 1 LAST PATH I15
J 0
(-7280 4852);
DISPLAY 0.340426 (-7280 4852);
PAINT GREEN (-7280 4852);
DISPLAY INVISIBLE (-7280 4852);
FORCEPROP 2 LAST CDS_LIB mstr_symbols
J 0
(-7325 4850);
PAINT ORANGE (-7325 4850);
DISPLAY INVISIBLE (-7325 4850);
FORCEPROP 1 LAST VOLTAGE 3.3V
J 0
(-7370 4807);
DISPLAY 0.340426 (-7370 4807);
PAINT SKYBLUE (-7370 4807);
DISPLAY INVISIBLE (-7370 4807);
FORCEPROP 1 LAST SIZE 1B
J 0
(-7280 4872);
DISPLAY 0.340426 (-7280 4872);
PAINT GREEN (-7280 4872);
DISPLAY INVISIBLE (-7280 4872);
FORCEPROP 1 LAST BODY_TYPE PLUMBING
J 0
(-7370 4807);
DISPLAY 0.340426 (-7370 4807);
PAINT GREEN (-7370 4807);
DISPLAY INVISIBLE (-7370 4807);
FORCEPROP 1 LAST HDL_POWER P3V3_STBY
J 0
(-7625 4725);
DISPLAY 0.872340 (-7625 4725);
PAINT ORANGE (-7625 4725);
DISPLAY INVISIBLE (-7625 4725);
FORCEADD OFFPAGE..2
(-5625 3625);
FORCEPROP 2 LAST $XR0 146 
J 0
(-5436 3625);
DISPLAY 0.638298 (-5436 3625);
PAINT MONO (-5436 3625);
FORCEPROP 2 LAST PATH I16
J 0
(-5425 3675);
DISPLAY 1.021277 (-5425 3675);
PAINT ORANGE (-5425 3675);
DISPLAY INVISIBLE (-5425 3675);
FORCEPROP 2 LAST CDS_LIB mstr_standard
J 0
(-5625 3625);
PAINT ORANGE (-5625 3625);
DISPLAY INVISIBLE (-5625 3625);
FORCEPROP 2 LAST $XRERR ?
J 0
(-5436 3625);
DISPLAY 0.638298 (-5436 3625);
PAINT MONO (-5436 3625);
DISPLAY INVISIBLE (-5436 3625);
FORCEPROP 1 LAST OFFPAGE TRUE
J 0
(-5300 3500);
DISPLAY 0.872340 (-5300 3500);
PAINT GREEN (-5300 3500);
DISPLAY INVISIBLE (-5300 3500);
FORCEPROP 1 LAST COMMENT_BODY TRUE
J 0
(-5670 3530);
DISPLAY 0.872340 (-5670 3530);
PAINT GREEN (-5670 3530);
DISPLAY INVISIBLE (-5670 3530);
FORCEADD OFFPAGE..2
(-5600 3475);
FORCEPROP 2 LAST $XR0 146 
J 0
(-5411 3475);
DISPLAY 0.638298 (-5411 3475);
PAINT MONO (-5411 3475);
FORCEPROP 2 LAST $XR1 247 
J 0
(-5411 3475);
DISPLAY 0.638298 (-5411 3475);
PAINT MONO (-5411 3475);
FORCEPROP 1 LAST COMMENT_BODY TRUE
J 0
(-5645 3380);
DISPLAY 0.872340 (-5645 3380);
PAINT GREEN (-5645 3380);
DISPLAY INVISIBLE (-5645 3380);
FORCEPROP 1 LAST OFFPAGE TRUE
J 0
(-5275 3350);
DISPLAY 0.872340 (-5275 3350);
PAINT GREEN (-5275 3350);
DISPLAY INVISIBLE (-5275 3350);
FORCEPROP 2 LAST $XRERR ?
J 0
(-5411 3475);
DISPLAY 0.638298 (-5411 3475);
PAINT MONO (-5411 3475);
DISPLAY INVISIBLE (-5411 3475);
FORCEPROP 2 LAST CDS_LIB mstr_standard
J 0
(-5600 3475);
PAINT MONO (-5600 3475);
DISPLAY INVISIBLE (-5600 3475);
FORCEPROP 2 LAST PATH I17
J 0
(-5400 3525);
DISPLAY 1.021277 (-5400 3525);
PAINT ORANGE (-5400 3525);
DISPLAY INVISIBLE (-5400 3525);
FORCEADD OFFPAGE..2
(-5600 3325);
FORCEPROP 2 LAST $XR0 146 
J 0
(-5411 3325);
DISPLAY 0.638298 (-5411 3325);
PAINT MONO (-5411 3325);
FORCEPROP 2 LAST $XR2 119 
J 0
(-5411 3325);
DISPLAY 0.638298 (-5411 3325);
PAINT MONO (-5411 3325);
FORCEPROP 2 LAST $XR1 191 
J 0
(-5411 3325);
DISPLAY 0.638298 (-5411 3325);
PAINT MONO (-5411 3325);
FORCEPROP 2 LAST PATH I18
J 0
(-5400 3375);
DISPLAY 1.021277 (-5400 3375);
PAINT ORANGE (-5400 3375);
DISPLAY INVISIBLE (-5400 3375);
FORCEPROP 2 LAST CDS_LIB mstr_standard
J 0
(-5600 3325);
PAINT ORANGE (-5600 3325);
DISPLAY INVISIBLE (-5600 3325);
FORCEPROP 2 LAST $XRERR ?
J 0
(-5411 3325);
DISPLAY 0.638298 (-5411 3325);
PAINT MONO (-5411 3325);
DISPLAY INVISIBLE (-5411 3325);
FORCEPROP 1 LAST OFFPAGE TRUE
J 0
(-5275 3200);
DISPLAY 0.872340 (-5275 3200);
PAINT GREEN (-5275 3200);
DISPLAY INVISIBLE (-5275 3200);
FORCEPROP 1 LAST COMMENT_BODY TRUE
J 0
(-5645 3230);
DISPLAY 0.872340 (-5645 3230);
PAINT GREEN (-5645 3230);
DISPLAY INVISIBLE (-5645 3230);
FORCEADD OFFPAGE..2
(-5600 3175);
FORCEPROP 2 LAST $XR0 146 
J 0
(-5411 3175);
DISPLAY 0.638298 (-5411 3175);
PAINT MONO (-5411 3175);
FORCEPROP 2 LAST $XR1 152 
J 0
(-5411 3175);
DISPLAY 0.638298 (-5411 3175);
PAINT MONO (-5411 3175);
FORCEPROP 2 LAST PATH I19
J 0
(-5400 3225);
DISPLAY 1.021277 (-5400 3225);
PAINT ORANGE (-5400 3225);
DISPLAY INVISIBLE (-5400 3225);
FORCEPROP 2 LAST CDS_LIB mstr_standard
J 0
(-5600 3175);
PAINT MONO (-5600 3175);
DISPLAY INVISIBLE (-5600 3175);
FORCEPROP 2 LAST $XRERR ?
J 0
(-5411 3175);
DISPLAY 0.638298 (-5411 3175);
PAINT MONO (-5411 3175);
DISPLAY INVISIBLE (-5411 3175);
FORCEPROP 1 LAST OFFPAGE TRUE
J 0
(-5275 3050);
DISPLAY 0.872340 (-5275 3050);
PAINT GREEN (-5275 3050);
DISPLAY INVISIBLE (-5275 3050);
FORCEPROP 1 LAST COMMENT_BODY TRUE
J 0
(-5645 3080);
DISPLAY 0.872340 (-5645 3080);
PAINT GREEN (-5645 3080);
DISPLAY INVISIBLE (-5645 3080);
FORCEADD RES..1
(-6900 4550);
FORCEPROP 1 LAST PART_NUMBER G21796-072
J 0
(-6725 4575);
DISPLAY 0.617021 (-6725 4575);
PAINT BLUE (-6725 4575);
FORCEPROP 1 LAST LOCATION R25W95
J 0
(-6950 4600);
DISPLAY 0.617021 (-6950 4600);
PAINT AQUA (-6950 4600);
FORCEPROP 1 LAST VALUE 4.75K
J 2
(-6750 4575);
DISPLAY 0.617021 (-6750 4575);
PAINT SKYBLUE (-6750 4575);
FORCEPROP 1 LAST MATERIAL CHIP
J 0
(-6750 4500);
DISPLAY 0.617021 (-6750 4500);
PAINT SKYBLUE (-6750 4500);
FORCEPROP 1 LAST TOLERANCE 1%
J 0
(-6825 4500);
DISPLAY 0.617021 (-6825 4500);
PAINT SKYBLUE (-6825 4500);
FORCEPROP 1 LAST WATTAGE 1/16W
J 2
(-6975 4500);
DISPLAY 0.617021 (-6975 4500);
PAINT SKYBLUE (-6975 4500);
FORCEPROP 1 LAST PACK_TYPE 0402
J 0
(-7075 4575);
DISPLAY 0.617021 (-7075 4575);
PAINT SKYBLUE (-7075 4575);
FORCEPROP 1 LAST PATH I2
J 0
(-6950 4700);
DISPLAY 0.978723 (-6950 4700);
PAINT WHITE (-6950 4700);
DISPLAY INVISIBLE (-6950 4700);
FORCEPROP 2 LAST ROOM BMC
J 0
(-6950 4650);
DISPLAY 1.021277 (-6950 4650);
PAINT ORANGE (-6950 4650);
DISPLAY INVISIBLE (-6950 4650);
FORCEPROP 2 LAST BOM_COST SM_CONTROLLER
J 0
(-6950 4700);
DISPLAY 1.021277 (-6950 4700);
PAINT ORANGE (-6950 4700);
DISPLAY INVISIBLE (-6950 4700);
FORCEPROP 2 LAST CDS_LIB mstr_discrete
J 0
(-6900 4550);
PAINT MONO (-6900 4550);
DISPLAY INVISIBLE (-6900 4550);
FORCEPROP 1 LASTPIN (-7000 4550) $PN 1
J 0
(-6988 4562);
DISPLAY 0.787234 (-6988 4562);
PAINT ORANGE (-6988 4562);
DISPLAY INVISIBLE (-6988 4562);
FORCEPROP 1 LASTPIN (-6800 4550) $PN 2
J 0
(-6838 4562);
DISPLAY 0.787234 (-6838 4562);
PAINT ORANGE (-6838 4562);
DISPLAY INVISIBLE (-6838 4562);
FORCEADD OFFPAGE..2
(-5925 2950);
FORCEPROP 2 LAST $XR0 55 
J 0
(-5736 2950);
DISPLAY 0.638298 (-5736 2950);
PAINT MONO (-5736 2950);
FORCEPROP 2 LAST $XR2 191 
J 0
(-5736 2950);
DISPLAY 0.638298 (-5736 2950);
PAINT MONO (-5736 2950);
FORCEPROP 2 LAST $XR1 146 
J 0
(-5736 2950);
DISPLAY 0.638298 (-5736 2950);
PAINT MONO (-5736 2950);
FORCEPROP 2 LAST PATH I20
J 0
(-5725 3000);
DISPLAY 1.021277 (-5725 3000);
PAINT ORANGE (-5725 3000);
DISPLAY INVISIBLE (-5725 3000);
FORCEPROP 2 LAST CDS_LIB mstr_standard
J 0
(-5925 2950);
PAINT MONO (-5925 2950);
DISPLAY INVISIBLE (-5925 2950);
FORCEPROP 2 LAST $XRERR ?
J 0
(-5736 2950);
DISPLAY 0.638298 (-5736 2950);
PAINT MONO (-5736 2950);
DISPLAY INVISIBLE (-5736 2950);
FORCEPROP 1 LAST OFFPAGE TRUE
J 0
(-5600 2825);
DISPLAY 0.872340 (-5600 2825);
PAINT GREEN (-5600 2825);
DISPLAY INVISIBLE (-5600 2825);
FORCEPROP 1 LAST COMMENT_BODY TRUE
J 0
(-5970 2855);
DISPLAY 0.872340 (-5970 2855);
PAINT GREEN (-5970 2855);
DISPLAY INVISIBLE (-5970 2855);
FORCEADD OFFPAGE..2
(-5925 2725);
FORCEPROP 2 LAST $XR0 144 
J 0
(-5736 2725);
DISPLAY 0.638298 (-5736 2725);
PAINT MONO (-5736 2725);
FORCEPROP 2 LAST $XR1 189 
J 0
(-5616 2725);
DISPLAY 0.638298 (-5616 2725);
PAINT MONO (-5616 2725);
FORCEPROP 2 LAST PATH I21
J 0
(-5600 2775);
DISPLAY 1.021277 (-5600 2775);
PAINT ORANGE (-5600 2775);
DISPLAY INVISIBLE (-5600 2775);
FORCEPROP 2 LAST CDS_LIB mstr_standard
J 0
(-5925 2725);
PAINT MONO (-5925 2725);
DISPLAY INVISIBLE (-5925 2725);
FORCEPROP 1 LAST OFFPAGE TRUE
J 0
(-5600 2600);
DISPLAY 0.872340 (-5600 2600);
PAINT GREEN (-5600 2600);
DISPLAY INVISIBLE (-5600 2600);
FORCEPROP 1 LAST COMMENT_BODY TRUE
J 0
(-5970 2630);
DISPLAY 0.872340 (-5970 2630);
PAINT GREEN (-5970 2630);
DISPLAY INVISIBLE (-5970 2630);
FORCEADD OFFPAGE..2
(-5925 2500);
FORCEPROP 2 LAST $XR1 186 
J 0
(-5616 2500);
DISPLAY 0.638298 (-5616 2500);
PAINT MONO (-5616 2500);
FORCEPROP 2 LAST $XR0 147 
J 0
(-5736 2500);
DISPLAY 0.638298 (-5736 2500);
PAINT MONO (-5736 2500);
FORCEPROP 2 LAST PATH I22
J 0
(-5600 2550);
DISPLAY 1.021277 (-5600 2550);
PAINT ORANGE (-5600 2550);
DISPLAY INVISIBLE (-5600 2550);
FORCEPROP 2 LAST CDS_LIB mstr_standard
J 0
(-5925 2500);
PAINT MONO (-5925 2500);
DISPLAY INVISIBLE (-5925 2500);
FORCEPROP 1 LAST OFFPAGE TRUE
J 0
(-5600 2375);
DISPLAY 0.872340 (-5600 2375);
PAINT GREEN (-5600 2375);
DISPLAY INVISIBLE (-5600 2375);
FORCEPROP 1 LAST COMMENT_BODY TRUE
J 0
(-5970 2405);
DISPLAY 0.872340 (-5970 2405);
PAINT GREEN (-5970 2405);
DISPLAY INVISIBLE (-5970 2405);
FORCEADD OFFPAGE..2
(-5925 2275);
FORCEPROP 2 LAST $XR0 147 
J 0
(-5736 2275);
DISPLAY 0.638298 (-5736 2275);
PAINT MONO (-5736 2275);
FORCEPROP 2 LAST PATH I23
J 0
(-5725 2325);
DISPLAY 1.021277 (-5725 2325);
PAINT ORANGE (-5725 2325);
DISPLAY INVISIBLE (-5725 2325);
FORCEPROP 2 LAST CDS_LIB mstr_standard
J 0
(-5925 2275);
PAINT MONO (-5925 2275);
DISPLAY INVISIBLE (-5925 2275);
FORCEPROP 1 LAST OFFPAGE TRUE
J 0
(-5600 2150);
DISPLAY 0.872340 (-5600 2150);
PAINT GREEN (-5600 2150);
DISPLAY INVISIBLE (-5600 2150);
FORCEPROP 1 LAST COMMENT_BODY TRUE
J 0
(-5970 2180);
DISPLAY 0.872340 (-5970 2180);
PAINT GREEN (-5970 2180);
DISPLAY INVISIBLE (-5970 2180);
FORCEADD OFFPAGE..2
(-5900 2075);
FORCEPROP 2 LAST $XR0 147 
J 0
(-5711 2075);
DISPLAY 0.638298 (-5711 2075);
PAINT MONO (-5711 2075);
FORCEPROP 2 LAST PATH I24
J 0
(-5700 2125);
DISPLAY 1.021277 (-5700 2125);
PAINT ORANGE (-5700 2125);
DISPLAY INVISIBLE (-5700 2125);
FORCEPROP 2 LAST CDS_LIB mstr_standard
J 0
(-5900 2075);
PAINT ORANGE (-5900 2075);
DISPLAY INVISIBLE (-5900 2075);
FORCEPROP 1 LAST OFFPAGE TRUE
J 0
(-5575 1950);
DISPLAY 0.872340 (-5575 1950);
PAINT GREEN (-5575 1950);
DISPLAY INVISIBLE (-5575 1950);
FORCEPROP 1 LAST COMMENT_BODY TRUE
J 0
(-5945 1980);
DISPLAY 0.872340 (-5945 1980);
PAINT GREEN (-5945 1980);
DISPLAY INVISIBLE (-5945 1980);
FORCEADD OFFPAGE..2
(-5900 1850);
FORCEPROP 2 LAST $XR0 147 
J 0
(-5711 1850);
DISPLAY 0.638298 (-5711 1850);
PAINT MONO (-5711 1850);
FORCEPROP 2 LAST PATH I25
J 0
(-5700 1900);
DISPLAY 1.021277 (-5700 1900);
PAINT ORANGE (-5700 1900);
DISPLAY INVISIBLE (-5700 1900);
FORCEPROP 2 LAST CDS_LIB mstr_standard
J 0
(-5900 1850);
PAINT MONO (-5900 1850);
DISPLAY INVISIBLE (-5900 1850);
FORCEPROP 1 LAST OFFPAGE TRUE
J 0
(-5575 1725);
DISPLAY 0.872340 (-5575 1725);
PAINT GREEN (-5575 1725);
DISPLAY INVISIBLE (-5575 1725);
FORCEPROP 1 LAST COMMENT_BODY TRUE
J 0
(-5945 1755);
DISPLAY 0.872340 (-5945 1755);
PAINT GREEN (-5945 1755);
DISPLAY INVISIBLE (-5945 1755);
FORCEADD OFFPAGE..2
(-5875 1675);
FORCEPROP 2 LAST $XR0 147 
J 0
(-5686 1675);
DISPLAY 0.638298 (-5686 1675);
PAINT MONO (-5686 1675);
FORCEPROP 2 LAST PATH I26
J 0
(-5675 1725);
DISPLAY 1.021277 (-5675 1725);
PAINT ORANGE (-5675 1725);
DISPLAY INVISIBLE (-5675 1725);
FORCEPROP 2 LAST CDS_LIB mstr_standard
J 0
(-5875 1675);
PAINT ORANGE (-5875 1675);
DISPLAY INVISIBLE (-5875 1675);
FORCEPROP 1 LAST OFFPAGE TRUE
J 0
(-5550 1550);
DISPLAY 0.872340 (-5550 1550);
PAINT GREEN (-5550 1550);
DISPLAY INVISIBLE (-5550 1550);
FORCEPROP 1 LAST COMMENT_BODY TRUE
J 0
(-5920 1580);
DISPLAY 0.872340 (-5920 1580);
PAINT GREEN (-5920 1580);
DISPLAY INVISIBLE (-5920 1580);
FORCEADD RES..1
(-6900 3475);
FORCEPROP 1 LAST PART_NUMBER G21796-072
J 0
(-6725 3500);
DISPLAY 0.617021 (-6725 3500);
PAINT BLUE (-6725 3500);
FORCEPROP 1 LAST LOCATION R25W101
J 0
(-6950 3525);
DISPLAY 0.617021 (-6950 3525);
PAINT AQUA (-6950 3525);
FORCEPROP 1 LAST WATTAGE 1/16W
J 2
(-6975 3425);
DISPLAY 0.617021 (-6975 3425);
PAINT SKYBLUE (-6975 3425);
FORCEPROP 1 LAST PACK_TYPE 0402
J 0
(-7075 3500);
DISPLAY 0.617021 (-7075 3500);
PAINT SKYBLUE (-7075 3500);
FORCEPROP 1 LAST TOLERANCE 1%
J 0
(-6825 3425);
DISPLAY 0.617021 (-6825 3425);
PAINT SKYBLUE (-6825 3425);
FORCEPROP 1 LAST VALUE 4.75K
J 2
(-6750 3500);
DISPLAY 0.617021 (-6750 3500);
PAINT SKYBLUE (-6750 3500);
FORCEPROP 1 LAST MATERIAL EMPTY
J 0
(-6750 3425);
DISPLAY 0.617021 (-6750 3425);
PAINT RED (-6750 3425);
FORCEPROP 1 LAST PATH I27
J 0
(-6950 3625);
DISPLAY 0.978723 (-6950 3625);
PAINT WHITE (-6950 3625);
DISPLAY INVISIBLE (-6950 3625);
FORCEPROP 1 LASTPIN (-7000 3475) $PN 1
J 0
(-6988 3487);
DISPLAY 0.787234 (-6988 3487);
PAINT ORANGE (-6988 3487);
DISPLAY INVISIBLE (-6988 3487);
FORCEPROP 2 LAST CDS_LIB mstr_discrete
J 0
(-6900 3475);
PAINT ORANGE (-6900 3475);
DISPLAY INVISIBLE (-6900 3475);
FORCEPROP 2 LAST ROOM BMC
J 0
(-6950 3575);
DISPLAY 1.021277 (-6950 3575);
PAINT ORANGE (-6950 3575);
DISPLAY INVISIBLE (-6950 3575);
FORCEPROP 1 LASTPIN (-6800 3475) $PN 2
J 0
(-6838 3487);
DISPLAY 0.787234 (-6838 3487);
PAINT ORANGE (-6838 3487);
DISPLAY INVISIBLE (-6838 3487);
FORCEPROP 2 LAST $SEC 1
J 0
(-6950 3675);
PAINT MONO (-6950 3675);
DISPLAY INVISIBLE (-6950 3675);
FORCEPROP 2 LAST CDS_SEC 1
J 0
(-6950 3675);
PAINT MONO (-6950 3675);
DISPLAY INVISIBLE (-6950 3675);
FORCEPROP 2 LAST BOM_COST SM_CONTROLLER
J 0
(-6950 3625);
DISPLAY 1.021277 (-6950 3625);
PAINT ORANGE (-6950 3625);
DISPLAY INVISIBLE (-6950 3625);
FORCEPROP 2 LAST CDS_LOCATION R25W101
J 0
(-6950 3525);
DISPLAY 0.617021 (-6950 3525);
PAINT AQUA (-6950 3525);
DISPLAY INVISIBLE (-6950 3525);
FORCEADD RES..1
(-6900 3325);
FORCEPROP 1 LAST LOCATION R25W102
J 0
(-6950 3375);
DISPLAY 0.617021 (-6950 3375);
PAINT AQUA (-6950 3375);
FORCEPROP 1 LAST PART_NUMBER G21796-072
J 0
(-6725 3350);
DISPLAY 0.617021 (-6725 3350);
PAINT BLUE (-6725 3350);
FORCEPROP 1 LAST MATERIAL CHIP
J 0
(-6750 3275);
DISPLAY 0.617021 (-6750 3275);
PAINT SKYBLUE (-6750 3275);
FORCEPROP 1 LAST PACK_TYPE 0402
J 0
(-7075 3350);
DISPLAY 0.617021 (-7075 3350);
PAINT SKYBLUE (-7075 3350);
FORCEPROP 1 LAST TOLERANCE 1%
J 0
(-6825 3275);
DISPLAY 0.617021 (-6825 3275);
PAINT SKYBLUE (-6825 3275);
FORCEPROP 1 LAST WATTAGE 1/16W
J 2
(-6975 3275);
DISPLAY 0.617021 (-6975 3275);
PAINT SKYBLUE (-6975 3275);
FORCEPROP 1 LAST VALUE 4.75K
J 2
(-6750 3350);
DISPLAY 0.617021 (-6750 3350);
PAINT SKYBLUE (-6750 3350);
FORCEPROP 1 LAST PATH I28
J 0
(-6950 3475);
DISPLAY 0.978723 (-6950 3475);
PAINT WHITE (-6950 3475);
DISPLAY INVISIBLE (-6950 3475);
FORCEPROP 2 LAST ROOM BMC
J 0
(-6950 3425);
DISPLAY 1.021277 (-6950 3425);
PAINT ORANGE (-6950 3425);
DISPLAY INVISIBLE (-6950 3425);
FORCEPROP 2 LAST BOM_COST SM_CONTROLLER
J 0
(-6950 3475);
DISPLAY 1.021277 (-6950 3475);
PAINT ORANGE (-6950 3475);
DISPLAY INVISIBLE (-6950 3475);
FORCEPROP 2 LAST CDS_LIB mstr_discrete
J 0
(-6900 3325);
PAINT MONO (-6900 3325);
DISPLAY INVISIBLE (-6900 3325);
FORCEPROP 1 LASTPIN (-7000 3325) $PN 1
J 0
(-6988 3337);
DISPLAY 0.787234 (-6988 3337);
PAINT ORANGE (-6988 3337);
DISPLAY INVISIBLE (-6988 3337);
FORCEPROP 1 LASTPIN (-6800 3325) $PN 2
J 0
(-6838 3337);
DISPLAY 0.787234 (-6838 3337);
PAINT ORANGE (-6838 3337);
DISPLAY INVISIBLE (-6838 3337);
FORCEADD RES..1
(-6900 3175);
FORCEPROP 1 LAST LOCATION R25W103
J 0
(-6950 3225);
DISPLAY 0.617021 (-6950 3225);
PAINT AQUA (-6950 3225);
FORCEPROP 1 LAST VALUE 4.75K
J 2
(-6750 3200);
DISPLAY 0.617021 (-6750 3200);
PAINT SKYBLUE (-6750 3200);
FORCEPROP 1 LAST TOLERANCE 1%
J 0
(-6825 3125);
DISPLAY 0.617021 (-6825 3125);
PAINT SKYBLUE (-6825 3125);
FORCEPROP 1 LAST MATERIAL EMPTY
J 0
(-6750 3125);
DISPLAY 0.617021 (-6750 3125);
PAINT RED (-6750 3125);
FORCEPROP 1 LAST PACK_TYPE 0402
J 0
(-7075 3200);
DISPLAY 0.617021 (-7075 3200);
PAINT SKYBLUE (-7075 3200);
FORCEPROP 1 LAST PART_NUMBER G21796-072
J 0
(-6725 3200);
DISPLAY 0.617021 (-6725 3200);
PAINT BLUE (-6725 3200);
FORCEPROP 1 LAST WATTAGE 1/16W
J 2
(-6975 3125);
DISPLAY 0.617021 (-6975 3125);
PAINT SKYBLUE (-6975 3125);
FORCEPROP 1 LAST PATH I29
J 0
(-6950 3325);
DISPLAY 0.978723 (-6950 3325);
PAINT WHITE (-6950 3325);
DISPLAY INVISIBLE (-6950 3325);
FORCEPROP 1 LASTPIN (-7000 3175) $PN 1
J 0
(-6988 3187);
DISPLAY 0.787234 (-6988 3187);
PAINT ORANGE (-6988 3187);
DISPLAY INVISIBLE (-6988 3187);
FORCEPROP 2 LAST CDS_LIB mstr_discrete
J 0
(-6900 3175);
PAINT ORANGE (-6900 3175);
DISPLAY INVISIBLE (-6900 3175);
FORCEPROP 2 LAST ROOM BMC
J 0
(-6950 3275);
DISPLAY 1.021277 (-6950 3275);
PAINT ORANGE (-6950 3275);
DISPLAY INVISIBLE (-6950 3275);
FORCEPROP 1 LASTPIN (-6800 3175) $PN 2
J 0
(-6838 3187);
DISPLAY 0.787234 (-6838 3187);
PAINT ORANGE (-6838 3187);
DISPLAY INVISIBLE (-6838 3187);
FORCEPROP 2 LAST $SEC 1
J 0
(-6950 3375);
PAINT MONO (-6950 3375);
DISPLAY INVISIBLE (-6950 3375);
FORCEPROP 2 LAST CDS_SEC 1
J 0
(-6950 3375);
PAINT MONO (-6950 3375);
DISPLAY INVISIBLE (-6950 3375);
FORCEPROP 2 LAST BOM_COST SM_CONTROLLER
J 0
(-6950 3325);
DISPLAY 1.021277 (-6950 3325);
PAINT ORANGE (-6950 3325);
DISPLAY INVISIBLE (-6950 3325);
FORCEPROP 2 LAST CDS_LOCATION R25W103
J 0
(-6950 3225);
DISPLAY 0.617021 (-6950 3225);
PAINT AQUA (-6950 3225);
DISPLAY INVISIBLE (-6950 3225);
FORCEADD OFFPAGE..2
(-5650 4675);
FORCEPROP 2 LAST $XR0 146 
J 0
(-5461 4650);
DISPLAY 0.638298 (-5461 4650);
PAINT MONO (-5461 4650);
FORCEPROP 2 LAST $XR1 162 
J 0
(-5386 4664);
DISPLAY 0.638298 (-5386 4664);
PAINT MONO (-5386 4664);
FORCEPROP 2 LAST $XR2 ?
J 0
(-5286 4661);
DISPLAY 0.638298 (-5286 4661);
PAINT MONO (-5286 4661);
FORCEPROP 2 LAST PATH I3
J 0
(-5275 4700);
DISPLAY 1.021277 (-5275 4700);
PAINT ORANGE (-5275 4700);
DISPLAY INVISIBLE (-5275 4700);
FORCEPROP 2 LAST CDS_LIB mstr_standard
J 0
(-5650 4675);
PAINT MONO (-5650 4675);
DISPLAY INVISIBLE (-5650 4675);
FORCEPROP 1 LAST OFFPAGE TRUE
J 0
(-5325 4550);
DISPLAY 0.872340 (-5325 4550);
PAINT GREEN (-5325 4550);
DISPLAY INVISIBLE (-5325 4550);
FORCEPROP 1 LAST COMMENT_BODY TRUE
J 0
(-5695 4580);
DISPLAY 0.872340 (-5695 4580);
PAINT GREEN (-5695 4580);
DISPLAY INVISIBLE (-5695 4580);
FORCEADD RES..1
(-6900 2950);
FORCEPROP 1 LAST VALUE 4.75K
J 2
(-6750 2975);
DISPLAY 0.617021 (-6750 2975);
PAINT SKYBLUE (-6750 2975);
FORCEPROP 1 LAST LOCATION R25W104
J 0
(-6950 3000);
DISPLAY 0.617021 (-6950 3000);
PAINT AQUA (-6950 3000);
FORCEPROP 1 LAST PACK_TYPE 0402
J 0
(-7075 2975);
DISPLAY 0.617021 (-7075 2975);
PAINT SKYBLUE (-7075 2975);
FORCEPROP 1 LAST PART_NUMBER G21796-072
J 0
(-6725 2975);
DISPLAY 0.617021 (-6725 2975);
PAINT BLUE (-6725 2975);
FORCEPROP 1 LAST MATERIAL EMPTY
J 0
(-6750 2900);
DISPLAY 0.617021 (-6750 2900);
PAINT RED (-6750 2900);
FORCEPROP 1 LAST TOLERANCE 1%
J 0
(-6825 2900);
DISPLAY 0.617021 (-6825 2900);
PAINT SKYBLUE (-6825 2900);
FORCEPROP 1 LAST WATTAGE 1/16W
J 2
(-6975 2900);
DISPLAY 0.617021 (-6975 2900);
PAINT SKYBLUE (-6975 2900);
FORCEPROP 1 LAST PATH I30
J 0
(-6950 3100);
DISPLAY 0.978723 (-6950 3100);
PAINT WHITE (-6950 3100);
DISPLAY INVISIBLE (-6950 3100);
FORCEPROP 2 LAST BOM_COST SM_CONTROLLER
J 0
(-6950 3100);
DISPLAY 1.021277 (-6950 3100);
PAINT ORANGE (-6950 3100);
DISPLAY INVISIBLE (-6950 3100);
FORCEPROP 2 LAST CDS_SEC 1
J 0
(-6950 3150);
PAINT MONO (-6950 3150);
DISPLAY INVISIBLE (-6950 3150);
FORCEPROP 2 LAST $SEC 1
J 0
(-6950 3150);
PAINT MONO (-6950 3150);
DISPLAY INVISIBLE (-6950 3150);
FORCEPROP 1 LASTPIN (-6800 2950) $PN 2
J 0
(-6838 2962);
DISPLAY 0.787234 (-6838 2962);
PAINT ORANGE (-6838 2962);
DISPLAY INVISIBLE (-6838 2962);
FORCEPROP 2 LAST ROOM BMC
J 0
(-6950 3050);
DISPLAY 1.021277 (-6950 3050);
PAINT ORANGE (-6950 3050);
DISPLAY INVISIBLE (-6950 3050);
FORCEPROP 2 LAST CDS_LIB mstr_discrete
J 0
(-6900 2950);
PAINT ORANGE (-6900 2950);
DISPLAY INVISIBLE (-6900 2950);
FORCEPROP 1 LASTPIN (-7000 2950) $PN 1
J 0
(-6988 2962);
DISPLAY 0.787234 (-6988 2962);
PAINT ORANGE (-6988 2962);
DISPLAY INVISIBLE (-6988 2962);
FORCEPROP 2 LAST CDS_LOCATION R25W104
J 0
(-6950 3000);
DISPLAY 0.617021 (-6950 3000);
PAINT AQUA (-6950 3000);
DISPLAY INVISIBLE (-6950 3000);
FORCEADD RES..1
(-6900 2725);
FORCEPROP 1 LAST MATERIAL EMPTY
J 0
(-6750 2675);
DISPLAY 0.617021 (-6750 2675);
PAINT RED (-6750 2675);
FORCEPROP 1 LAST TOLERANCE 1%
J 0
(-6825 2675);
DISPLAY 0.617021 (-6825 2675);
PAINT SKYBLUE (-6825 2675);
FORCEPROP 1 LAST WATTAGE 1/16W
J 2
(-6975 2675);
DISPLAY 0.617021 (-6975 2675);
PAINT SKYBLUE (-6975 2675);
FORCEPROP 1 LAST PACK_TYPE 0402
J 0
(-7075 2750);
DISPLAY 0.617021 (-7075 2750);
PAINT SKYBLUE (-7075 2750);
FORCEPROP 1 LAST LOCATION R25W105
J 0
(-6950 2775);
DISPLAY 0.617021 (-6950 2775);
PAINT AQUA (-6950 2775);
FORCEPROP 1 LAST VALUE 4.75K
J 2
(-6750 2750);
DISPLAY 0.617021 (-6750 2750);
PAINT SKYBLUE (-6750 2750);
FORCEPROP 1 LAST PART_NUMBER G21796-072
J 0
(-6725 2750);
DISPLAY 0.617021 (-6725 2750);
PAINT BLUE (-6725 2750);
FORCEPROP 1 LAST PATH I31
J 0
(-6950 2875);
DISPLAY 0.978723 (-6950 2875);
PAINT WHITE (-6950 2875);
DISPLAY INVISIBLE (-6950 2875);
FORCEPROP 2 LAST BOM_COST SM_CONTROLLER
J 0
(-6950 2875);
DISPLAY 1.021277 (-6950 2875);
PAINT ORANGE (-6950 2875);
DISPLAY INVISIBLE (-6950 2875);
FORCEPROP 2 LAST CDS_SEC 1
J 0
(-6950 2925);
PAINT MONO (-6950 2925);
DISPLAY INVISIBLE (-6950 2925);
FORCEPROP 2 LAST $SEC 1
J 0
(-6950 2925);
PAINT MONO (-6950 2925);
DISPLAY INVISIBLE (-6950 2925);
FORCEPROP 1 LASTPIN (-6800 2725) $PN 2
J 0
(-6838 2737);
DISPLAY 0.787234 (-6838 2737);
PAINT ORANGE (-6838 2737);
DISPLAY INVISIBLE (-6838 2737);
FORCEPROP 2 LAST ROOM BMC
J 0
(-6950 2825);
DISPLAY 1.021277 (-6950 2825);
PAINT ORANGE (-6950 2825);
DISPLAY INVISIBLE (-6950 2825);
FORCEPROP 2 LAST CDS_LIB mstr_discrete
J 0
(-6900 2725);
PAINT ORANGE (-6900 2725);
DISPLAY INVISIBLE (-6900 2725);
FORCEPROP 1 LASTPIN (-7000 2725) $PN 1
J 0
(-6988 2737);
DISPLAY 0.787234 (-6988 2737);
PAINT ORANGE (-6988 2737);
DISPLAY INVISIBLE (-6988 2737);
FORCEPROP 2 LAST CDS_LOCATION R25W105
J 0
(-6950 2775);
DISPLAY 0.617021 (-6950 2775);
PAINT AQUA (-6950 2775);
DISPLAY INVISIBLE (-6950 2775);
FORCEADD RES..1
(-6900 2500);
FORCEPROP 1 LAST TOLERANCE 1%
J 0
(-6825 2450);
DISPLAY 0.617021 (-6825 2450);
PAINT SKYBLUE (-6825 2450);
FORCEPROP 1 LAST VALUE 4.75K
J 2
(-6750 2525);
DISPLAY 0.617021 (-6750 2525);
PAINT SKYBLUE (-6750 2525);
FORCEPROP 1 LAST WATTAGE 1/16W
J 2
(-6975 2450);
DISPLAY 0.617021 (-6975 2450);
PAINT SKYBLUE (-6975 2450);
FORCEPROP 1 LAST PACK_TYPE 0402
J 0
(-7075 2525);
DISPLAY 0.617021 (-7075 2525);
PAINT SKYBLUE (-7075 2525);
FORCEPROP 1 LAST MATERIAL EMPTY
J 0
(-6750 2450);
DISPLAY 0.617021 (-6750 2450);
PAINT RED (-6750 2450);
FORCEPROP 1 LAST LOCATION R25W106
J 0
(-6950 2550);
DISPLAY 0.617021 (-6950 2550);
PAINT AQUA (-6950 2550);
FORCEPROP 1 LAST PART_NUMBER G21796-072
J 0
(-6725 2525);
DISPLAY 0.617021 (-6725 2525);
PAINT BLUE (-6725 2525);
FORCEPROP 1 LAST PATH I32
J 0
(-6950 2650);
DISPLAY 0.978723 (-6950 2650);
PAINT WHITE (-6950 2650);
DISPLAY INVISIBLE (-6950 2650);
FORCEPROP 2 LAST BOM_COST SM_CONTROLLER
J 0
(-6950 2650);
DISPLAY 1.021277 (-6950 2650);
PAINT ORANGE (-6950 2650);
DISPLAY INVISIBLE (-6950 2650);
FORCEPROP 2 LAST CDS_SEC 1
J 0
(-6950 2700);
PAINT MONO (-6950 2700);
DISPLAY INVISIBLE (-6950 2700);
FORCEPROP 2 LAST $SEC 1
J 0
(-6950 2700);
PAINT MONO (-6950 2700);
DISPLAY INVISIBLE (-6950 2700);
FORCEPROP 1 LASTPIN (-6800 2500) $PN 2
J 0
(-6838 2512);
DISPLAY 0.787234 (-6838 2512);
PAINT ORANGE (-6838 2512);
DISPLAY INVISIBLE (-6838 2512);
FORCEPROP 2 LAST ROOM BMC
J 0
(-6950 2600);
DISPLAY 1.021277 (-6950 2600);
PAINT ORANGE (-6950 2600);
DISPLAY INVISIBLE (-6950 2600);
FORCEPROP 2 LAST CDS_LIB mstr_discrete
J 0
(-6900 2500);
PAINT ORANGE (-6900 2500);
DISPLAY INVISIBLE (-6900 2500);
FORCEPROP 1 LASTPIN (-7000 2500) $PN 1
J 0
(-6988 2512);
DISPLAY 0.787234 (-6988 2512);
PAINT ORANGE (-6988 2512);
DISPLAY INVISIBLE (-6988 2512);
FORCEPROP 2 LAST CDS_LOCATION R25W106
J 0
(-6950 2550);
DISPLAY 0.617021 (-6950 2550);
PAINT AQUA (-6950 2550);
DISPLAY INVISIBLE (-6950 2550);
FORCEADD RES..1
(-6900 2275);
FORCEPROP 1 LAST WATTAGE 1/16W
J 2
(-6975 2225);
DISPLAY 0.617021 (-6975 2225);
PAINT SKYBLUE (-6975 2225);
FORCEPROP 1 LAST PACK_TYPE 0402
J 0
(-7075 2300);
DISPLAY 0.617021 (-7075 2300);
PAINT SKYBLUE (-7075 2300);
FORCEPROP 1 LAST MATERIAL EMPTY
J 0
(-6750 2225);
DISPLAY 0.617021 (-6750 2225);
PAINT RED (-6750 2225);
FORCEPROP 1 LAST TOLERANCE 1%
J 0
(-6825 2225);
DISPLAY 0.617021 (-6825 2225);
PAINT SKYBLUE (-6825 2225);
FORCEPROP 1 LAST VALUE 4.75K
J 2
(-6750 2300);
DISPLAY 0.617021 (-6750 2300);
PAINT SKYBLUE (-6750 2300);
FORCEPROP 1 LAST PART_NUMBER G21796-072
J 0
(-6725 2300);
DISPLAY 0.617021 (-6725 2300);
PAINT BLUE (-6725 2300);
FORCEPROP 1 LAST LOCATION R25W107
J 0
(-6950 2325);
DISPLAY 0.617021 (-6950 2325);
PAINT AQUA (-6950 2325);
FORCEPROP 1 LAST PATH I33
J 0
(-6950 2425);
DISPLAY 0.978723 (-6950 2425);
PAINT WHITE (-6950 2425);
DISPLAY INVISIBLE (-6950 2425);
FORCEPROP 2 LAST BOM_COST SM_CONTROLLER
J 0
(-6950 2425);
DISPLAY 1.021277 (-6950 2425);
PAINT ORANGE (-6950 2425);
DISPLAY INVISIBLE (-6950 2425);
FORCEPROP 2 LAST CDS_SEC 1
J 0
(-6950 2475);
PAINT MONO (-6950 2475);
DISPLAY INVISIBLE (-6950 2475);
FORCEPROP 2 LAST $SEC 1
J 0
(-6950 2475);
PAINT MONO (-6950 2475);
DISPLAY INVISIBLE (-6950 2475);
FORCEPROP 1 LASTPIN (-6800 2275) $PN 2
J 0
(-6838 2287);
DISPLAY 0.787234 (-6838 2287);
PAINT ORANGE (-6838 2287);
DISPLAY INVISIBLE (-6838 2287);
FORCEPROP 2 LAST ROOM BMC
J 0
(-6950 2375);
DISPLAY 1.021277 (-6950 2375);
PAINT ORANGE (-6950 2375);
DISPLAY INVISIBLE (-6950 2375);
FORCEPROP 2 LAST CDS_LIB mstr_discrete
J 0
(-6900 2275);
PAINT ORANGE (-6900 2275);
DISPLAY INVISIBLE (-6900 2275);
FORCEPROP 1 LASTPIN (-7000 2275) $PN 1
J 0
(-6988 2287);
DISPLAY 0.787234 (-6988 2287);
PAINT ORANGE (-6988 2287);
DISPLAY INVISIBLE (-6988 2287);
FORCEPROP 2 LAST CDS_LOCATION R25W107
J 0
(-6950 2325);
DISPLAY 0.617021 (-6950 2325);
PAINT AQUA (-6950 2325);
DISPLAY INVISIBLE (-6950 2325);
FORCEADD RES..1
(-6875 2075);
FORCEPROP 1 LAST PART_NUMBER G21796-072
J 0
(-6700 2100);
DISPLAY 0.617021 (-6700 2100);
PAINT BLUE (-6700 2100);
FORCEPROP 1 LAST WATTAGE 1/16W
J 2
(-6950 2025);
DISPLAY 0.617021 (-6950 2025);
PAINT SKYBLUE (-6950 2025);
FORCEPROP 1 LAST LOCATION R25W108
J 0
(-6925 2125);
DISPLAY 0.617021 (-6925 2125);
PAINT AQUA (-6925 2125);
FORCEPROP 1 LAST VALUE 4.75K
J 2
(-6725 2100);
DISPLAY 0.617021 (-6725 2100);
PAINT SKYBLUE (-6725 2100);
FORCEPROP 1 LAST PACK_TYPE 0402
J 0
(-7050 2100);
DISPLAY 0.617021 (-7050 2100);
PAINT SKYBLUE (-7050 2100);
FORCEPROP 1 LAST MATERIAL CHIP
J 0
(-6725 2025);
DISPLAY 0.617021 (-6725 2025);
PAINT SKYBLUE (-6725 2025);
FORCEPROP 1 LAST TOLERANCE 1%
J 0
(-6800 2025);
DISPLAY 0.617021 (-6800 2025);
PAINT SKYBLUE (-6800 2025);
FORCEPROP 1 LAST PATH I34
J 0
(-6925 2225);
DISPLAY 0.978723 (-6925 2225);
PAINT WHITE (-6925 2225);
DISPLAY INVISIBLE (-6925 2225);
FORCEPROP 2 LAST CDS_LIB mstr_discrete
J 0
(-6875 2075);
PAINT MONO (-6875 2075);
DISPLAY INVISIBLE (-6875 2075);
FORCEPROP 2 LAST BOM_COST SM_CONTROLLER
J 0
(-6925 2225);
DISPLAY 1.021277 (-6925 2225);
PAINT ORANGE (-6925 2225);
DISPLAY INVISIBLE (-6925 2225);
FORCEPROP 2 LAST ROOM BMC
J 0
(-6925 2175);
DISPLAY 1.021277 (-6925 2175);
PAINT ORANGE (-6925 2175);
DISPLAY INVISIBLE (-6925 2175);
FORCEPROP 1 LASTPIN (-6975 2075) $PN 1
J 0
(-6963 2087);
DISPLAY 0.787234 (-6963 2087);
PAINT ORANGE (-6963 2087);
DISPLAY INVISIBLE (-6963 2087);
FORCEPROP 1 LASTPIN (-6775 2075) $PN 2
J 0
(-6813 2087);
DISPLAY 0.787234 (-6813 2087);
PAINT ORANGE (-6813 2087);
DISPLAY INVISIBLE (-6813 2087);
FORCEADD RES..1
(-6875 1850);
FORCEPROP 1 LAST VALUE 4.75K
J 2
(-6725 1875);
DISPLAY 0.617021 (-6725 1875);
PAINT SKYBLUE (-6725 1875);
FORCEPROP 1 LAST LOCATION R25W109
J 0
(-6925 1900);
DISPLAY 0.617021 (-6925 1900);
PAINT AQUA (-6925 1900);
FORCEPROP 1 LAST TOLERANCE 1%
J 0
(-6800 1800);
DISPLAY 0.617021 (-6800 1800);
PAINT SKYBLUE (-6800 1800);
FORCEPROP 1 LAST MATERIAL EMPTY
J 0
(-6725 1800);
DISPLAY 0.617021 (-6725 1800);
PAINT RED (-6725 1800);
FORCEPROP 1 LAST PART_NUMBER G21796-072
J 0
(-6700 1875);
DISPLAY 0.617021 (-6700 1875);
PAINT BLUE (-6700 1875);
FORCEPROP 1 LAST PACK_TYPE 0402
J 0
(-7050 1875);
DISPLAY 0.617021 (-7050 1875);
PAINT SKYBLUE (-7050 1875);
FORCEPROP 1 LAST WATTAGE 1/16W
J 2
(-6950 1800);
DISPLAY 0.617021 (-6950 1800);
PAINT SKYBLUE (-6950 1800);
FORCEPROP 1 LAST PATH I35
J 0
(-6925 2000);
DISPLAY 0.978723 (-6925 2000);
PAINT WHITE (-6925 2000);
DISPLAY INVISIBLE (-6925 2000);
FORCEPROP 2 LAST BOM_COST SM_CONTROLLER
J 0
(-6925 2000);
DISPLAY 1.021277 (-6925 2000);
PAINT ORANGE (-6925 2000);
DISPLAY INVISIBLE (-6925 2000);
FORCEPROP 2 LAST CDS_SEC 1
J 0
(-6925 2050);
PAINT MONO (-6925 2050);
DISPLAY INVISIBLE (-6925 2050);
FORCEPROP 2 LAST $SEC 1
J 0
(-6925 2050);
PAINT MONO (-6925 2050);
DISPLAY INVISIBLE (-6925 2050);
FORCEPROP 1 LASTPIN (-6775 1850) $PN 2
J 0
(-6813 1862);
DISPLAY 0.787234 (-6813 1862);
PAINT ORANGE (-6813 1862);
DISPLAY INVISIBLE (-6813 1862);
FORCEPROP 2 LAST ROOM BMC
J 0
(-6925 1950);
DISPLAY 1.021277 (-6925 1950);
PAINT ORANGE (-6925 1950);
DISPLAY INVISIBLE (-6925 1950);
FORCEPROP 2 LAST CDS_LIB mstr_discrete
J 0
(-6875 1850);
PAINT ORANGE (-6875 1850);
DISPLAY INVISIBLE (-6875 1850);
FORCEPROP 1 LASTPIN (-6975 1850) $PN 1
J 0
(-6963 1862);
DISPLAY 0.787234 (-6963 1862);
PAINT ORANGE (-6963 1862);
DISPLAY INVISIBLE (-6963 1862);
FORCEPROP 2 LAST CDS_LOCATION R25W109
J 0
(-6925 1900);
DISPLAY 0.617021 (-6925 1900);
PAINT AQUA (-6925 1900);
DISPLAY INVISIBLE (-6925 1900);
FORCEADD RES..1
(-6850 1675);
FORCEPROP 1 LAST LOCATION R25W110
J 0
(-6900 1725);
DISPLAY 0.617021 (-6900 1725);
PAINT AQUA (-6900 1725);
FORCEPROP 1 LAST TOLERANCE 1%
J 0
(-6775 1625);
DISPLAY 0.617021 (-6775 1625);
PAINT SKYBLUE (-6775 1625);
FORCEPROP 1 LAST WATTAGE 1/16W
J 2
(-6925 1625);
DISPLAY 0.617021 (-6925 1625);
PAINT SKYBLUE (-6925 1625);
FORCEPROP 1 LAST PACK_TYPE 0402
J 0
(-7025 1700);
DISPLAY 0.617021 (-7025 1700);
PAINT SKYBLUE (-7025 1700);
FORCEPROP 1 LAST MATERIAL CHIP
J 0
(-6700 1625);
DISPLAY 0.617021 (-6700 1625);
PAINT SKYBLUE (-6700 1625);
FORCEPROP 1 LAST VALUE 4.75K
J 2
(-6700 1700);
DISPLAY 0.617021 (-6700 1700);
PAINT SKYBLUE (-6700 1700);
FORCEPROP 1 LAST PART_NUMBER G21796-072
J 0
(-6675 1700);
DISPLAY 0.617021 (-6675 1700);
PAINT BLUE (-6675 1700);
FORCEPROP 1 LAST PATH I36
J 0
(-6900 1825);
DISPLAY 0.978723 (-6900 1825);
PAINT WHITE (-6900 1825);
DISPLAY INVISIBLE (-6900 1825);
FORCEPROP 2 LAST CDS_LIB mstr_discrete
J 0
(-6850 1675);
PAINT MONO (-6850 1675);
DISPLAY INVISIBLE (-6850 1675);
FORCEPROP 2 LAST BOM_COST SM_CONTROLLER
J 0
(-6900 1825);
DISPLAY 1.021277 (-6900 1825);
PAINT ORANGE (-6900 1825);
DISPLAY INVISIBLE (-6900 1825);
FORCEPROP 2 LAST ROOM BMC
J 0
(-6900 1775);
DISPLAY 1.021277 (-6900 1775);
PAINT ORANGE (-6900 1775);
DISPLAY INVISIBLE (-6900 1775);
FORCEPROP 1 LASTPIN (-6950 1675) $PN 1
J 0
(-6938 1687);
DISPLAY 0.787234 (-6938 1687);
PAINT ORANGE (-6938 1687);
DISPLAY INVISIBLE (-6938 1687);
FORCEPROP 1 LASTPIN (-6750 1675) $PN 2
J 0
(-6788 1687);
DISPLAY 0.787234 (-6788 1687);
PAINT ORANGE (-6788 1687);
DISPLAY INVISIBLE (-6788 1687);
FORCEADD OFFPAGE..2
(-5850 1400);
FORCEPROP 2 LAST $XR0 139 
J 0
(-5661 1400);
DISPLAY 0.638298 (-5661 1400);
PAINT MONO (-5661 1400);
FORCEPROP 2 LAST $XR1 147 
J 0
(-5541 1400);
DISPLAY 0.638298 (-5541 1400);
PAINT MONO (-5541 1400);
FORCEPROP 2 LAST $XR2 121 
J 0
(-5421 1400);
DISPLAY 0.638298 (-5421 1400);
PAINT MONO (-5421 1400);
FORCEPROP 2 LAST PATH I37
J 0
(-5400 1450);
DISPLAY 1.021277 (-5400 1450);
PAINT ORANGE (-5400 1450);
DISPLAY INVISIBLE (-5400 1450);
FORCEPROP 2 LAST CDS_LIB mstr_standard
J 0
(-5850 1400);
PAINT MONO (-5850 1400);
DISPLAY INVISIBLE (-5850 1400);
FORCEPROP 1 LAST OFFPAGE TRUE
J 0
(-5525 1275);
DISPLAY 0.872340 (-5525 1275);
PAINT GREEN (-5525 1275);
DISPLAY INVISIBLE (-5525 1275);
FORCEPROP 1 LAST COMMENT_BODY TRUE
J 0
(-5895 1305);
DISPLAY 0.872340 (-5895 1305);
PAINT GREEN (-5895 1305);
DISPLAY INVISIBLE (-5895 1305);
FORCEADD OFFPAGE..2
(-5850 1175);
FORCEPROP 2 LAST $XR0 147 
J 0
(-5641 1175);
DISPLAY 0.638298 (-5641 1175);
PAINT MONO (-5641 1175);
FORCEPROP 2 LAST PATH I38
J 0
(-5625 1225);
DISPLAY 1.021277 (-5625 1225);
PAINT ORANGE (-5625 1225);
DISPLAY INVISIBLE (-5625 1225);
FORCEPROP 2 LAST CDS_LIB mstr_standard
J 0
(-5850 1175);
PAINT MONO (-5850 1175);
DISPLAY INVISIBLE (-5850 1175);
FORCEPROP 1 LAST OFFPAGE TRUE
J 0
(-5525 1050);
DISPLAY 0.872340 (-5525 1050);
PAINT GREEN (-5525 1050);
DISPLAY INVISIBLE (-5525 1050);
FORCEPROP 1 LAST COMMENT_BODY TRUE
J 0
(-5895 1080);
DISPLAY 0.872340 (-5895 1080);
PAINT GREEN (-5895 1080);
DISPLAY INVISIBLE (-5895 1080);
FORCEADD OFFPAGE..2
(-5925 950);
FORCEPROP 2 LAST $XR0 147 
J 0
(-5736 950);
DISPLAY 0.638298 (-5736 950);
PAINT MONO (-5736 950);
FORCEPROP 2 LAST PATH I39
J 0
(-5725 1000);
DISPLAY 1.021277 (-5725 1000);
PAINT ORANGE (-5725 1000);
DISPLAY INVISIBLE (-5725 1000);
FORCEPROP 2 LAST CDS_LIB mstr_standard
J 0
(-5925 950);
PAINT MONO (-5925 950);
DISPLAY INVISIBLE (-5925 950);
FORCEPROP 1 LAST OFFPAGE TRUE
J 0
(-5600 825);
DISPLAY 0.872340 (-5600 825);
PAINT GREEN (-5600 825);
DISPLAY INVISIBLE (-5600 825);
FORCEPROP 1 LAST COMMENT_BODY TRUE
J 0
(-5970 855);
DISPLAY 0.872340 (-5970 855);
PAINT GREEN (-5970 855);
DISPLAY INVISIBLE (-5970 855);
FORCEADD OFFPAGE..2
(-5650 4550);
FORCEPROP 2 LAST $XR1 162 
J 0
(-5461 4550);
DISPLAY 0.638298 (-5461 4550);
PAINT MONO (-5461 4550);
FORCEPROP 2 LAST $XR0 146 
J 0
(-5386 4550);
DISPLAY 0.638298 (-5386 4550);
PAINT MONO (-5386 4550);
FORCEPROP 2 LAST $XR2 246 
J 0
(-5286 4550);
DISPLAY 0.638298 (-5286 4550);
PAINT MONO (-5286 4550);
FORCEPROP 2 LAST PATH I4
J 0
(-5275 4600);
DISPLAY 1.021277 (-5275 4600);
PAINT ORANGE (-5275 4600);
DISPLAY INVISIBLE (-5275 4600);
FORCEPROP 2 LAST CDS_LIB mstr_standard
J 0
(-5650 4550);
PAINT ORANGE (-5650 4550);
DISPLAY INVISIBLE (-5650 4550);
FORCEPROP 1 LAST OFFPAGE TRUE
J 0
(-5325 4425);
DISPLAY 0.872340 (-5325 4425);
PAINT GREEN (-5325 4425);
DISPLAY INVISIBLE (-5325 4425);
FORCEPROP 1 LAST COMMENT_BODY TRUE
J 0
(-5695 4455);
DISPLAY 0.872340 (-5695 4455);
PAINT GREEN (-5695 4455);
DISPLAY INVISIBLE (-5695 4455);
FORCEADD OFFPAGE..2
(-5925 725);
FORCEPROP 2 LAST $XR0 147 
J 0
(-5736 725);
DISPLAY 0.638298 (-5736 725);
PAINT MONO (-5736 725);
FORCEPROP 2 LAST PATH I40
J 0
(-5725 775);
DISPLAY 1.021277 (-5725 775);
PAINT ORANGE (-5725 775);
DISPLAY INVISIBLE (-5725 775);
FORCEPROP 2 LAST CDS_LIB mstr_standard
J 0
(-5925 725);
PAINT MONO (-5925 725);
DISPLAY INVISIBLE (-5925 725);
FORCEPROP 1 LAST OFFPAGE TRUE
J 0
(-5600 600);
DISPLAY 0.872340 (-5600 600);
PAINT GREEN (-5600 600);
DISPLAY INVISIBLE (-5600 600);
FORCEPROP 1 LAST COMMENT_BODY TRUE
J 0
(-5970 630);
DISPLAY 0.872340 (-5970 630);
PAINT GREEN (-5970 630);
DISPLAY INVISIBLE (-5970 630);
FORCEADD OFFPAGE..2
(-5900 475);
FORCEPROP 2 LAST $XR0 147 
J 0
(-5711 475);
DISPLAY 0.638298 (-5711 475);
PAINT MONO (-5711 475);
FORCEPROP 2 LAST PATH I41
J 0
(-5700 525);
DISPLAY 1.021277 (-5700 525);
PAINT ORANGE (-5700 525);
DISPLAY INVISIBLE (-5700 525);
FORCEPROP 2 LAST CDS_LIB mstr_standard
J 0
(-5900 475);
PAINT ORANGE (-5900 475);
DISPLAY INVISIBLE (-5900 475);
FORCEPROP 1 LAST OFFPAGE TRUE
J 0
(-5575 350);
DISPLAY 0.872340 (-5575 350);
PAINT GREEN (-5575 350);
DISPLAY INVISIBLE (-5575 350);
FORCEPROP 1 LAST COMMENT_BODY TRUE
J 0
(-5945 380);
DISPLAY 0.872340 (-5945 380);
PAINT GREEN (-5945 380);
DISPLAY INVISIBLE (-5945 380);
FORCEADD OFFPAGE..2
(-5900 225);
FORCEPROP 2 LAST $XR2 190 
J 0
(-5591 189);
DISPLAY 0.638298 (-5591 189);
PAINT MONO (-5591 189);
FORCEPROP 2 LAST $XR1 183 
J 0
(-5711 189);
DISPLAY 0.638298 (-5711 189);
PAINT MONO (-5711 189);
FORCEPROP 2 LAST $XR0 145 
J 0
(-5711 225);
DISPLAY 0.638298 (-5711 225);
PAINT MONO (-5711 225);
FORCEPROP 2 LAST $XR3 158 
J 0
(-5471 189);
DISPLAY 0.638298 (-5471 189);
PAINT MONO (-5471 189);
FORCEPROP 2 LAST PATH I42
J 0
(-5700 275);
DISPLAY 1.021277 (-5700 275);
PAINT ORANGE (-5700 275);
DISPLAY INVISIBLE (-5700 275);
FORCEPROP 2 LAST CDS_LIB mstr_standard
J 0
(-5900 225);
PAINT MONO (-5900 225);
DISPLAY INVISIBLE (-5900 225);
FORCEPROP 1 LAST OFFPAGE TRUE
J 0
(-5575 100);
DISPLAY 0.872340 (-5575 100);
PAINT GREEN (-5575 100);
DISPLAY INVISIBLE (-5575 100);
FORCEPROP 1 LAST COMMENT_BODY TRUE
J 0
(-5945 130);
DISPLAY 0.872340 (-5945 130);
PAINT GREEN (-5945 130);
DISPLAY INVISIBLE (-5945 130);
FORCEADD RES..1
(-6900 1400);
FORCEPROP 1 LAST PART_NUMBER G21796-072
J 0
(-6725 1425);
DISPLAY 0.617021 (-6725 1425);
PAINT BLUE (-6725 1425);
FORCEPROP 1 LAST VALUE 4.75K
J 2
(-6750 1425);
DISPLAY 0.617021 (-6750 1425);
PAINT SKYBLUE (-6750 1425);
FORCEPROP 1 LAST LOCATION R25W111
J 0
(-6950 1450);
DISPLAY 0.617021 (-6950 1450);
PAINT AQUA (-6950 1450);
FORCEPROP 1 LAST PACK_TYPE 0402
J 0
(-7075 1425);
DISPLAY 0.617021 (-7075 1425);
PAINT SKYBLUE (-7075 1425);
FORCEPROP 1 LAST MATERIAL EMPTY
J 0
(-6750 1350);
DISPLAY 0.617021 (-6750 1350);
PAINT RED (-6750 1350);
FORCEPROP 1 LAST WATTAGE 1/16W
J 2
(-6975 1350);
DISPLAY 0.617021 (-6975 1350);
PAINT SKYBLUE (-6975 1350);
FORCEPROP 1 LAST TOLERANCE 1%
J 0
(-6825 1350);
DISPLAY 0.617021 (-6825 1350);
PAINT SKYBLUE (-6825 1350);
FORCEPROP 1 LAST PATH I43
J 0
(-6950 1550);
DISPLAY 0.978723 (-6950 1550);
PAINT WHITE (-6950 1550);
DISPLAY INVISIBLE (-6950 1550);
FORCEPROP 2 LAST BOM_COST SM_CONTROLLER
J 0
(-6950 1550);
DISPLAY 1.021277 (-6950 1550);
PAINT ORANGE (-6950 1550);
DISPLAY INVISIBLE (-6950 1550);
FORCEPROP 2 LAST CDS_SEC 1
J 0
(-6950 1600);
PAINT MONO (-6950 1600);
DISPLAY INVISIBLE (-6950 1600);
FORCEPROP 2 LAST $SEC 1
J 0
(-6950 1600);
PAINT MONO (-6950 1600);
DISPLAY INVISIBLE (-6950 1600);
FORCEPROP 1 LASTPIN (-6800 1400) $PN 2
J 0
(-6838 1412);
DISPLAY 0.787234 (-6838 1412);
PAINT ORANGE (-6838 1412);
DISPLAY INVISIBLE (-6838 1412);
FORCEPROP 2 LAST ROOM BMC
J 0
(-6950 1500);
DISPLAY 1.021277 (-6950 1500);
PAINT ORANGE (-6950 1500);
DISPLAY INVISIBLE (-6950 1500);
FORCEPROP 2 LAST CDS_LIB mstr_discrete
J 0
(-6900 1400);
PAINT ORANGE (-6900 1400);
DISPLAY INVISIBLE (-6900 1400);
FORCEPROP 1 LASTPIN (-7000 1400) $PN 1
J 0
(-6988 1412);
DISPLAY 0.787234 (-6988 1412);
PAINT ORANGE (-6988 1412);
DISPLAY INVISIBLE (-6988 1412);
FORCEPROP 2 LAST CDS_LOCATION R25W111
J 0
(-6950 1450);
DISPLAY 0.617021 (-6950 1450);
PAINT AQUA (-6950 1450);
DISPLAY INVISIBLE (-6950 1450);
FORCEADD RES..1
(-6900 1175);
FORCEPROP 1 LAST LOCATION R25W112
J 0
(-6950 1225);
DISPLAY 0.617021 (-6950 1225);
PAINT AQUA (-6950 1225);
FORCEPROP 1 LAST MATERIAL EMPTY
J 0
(-6750 1125);
DISPLAY 0.617021 (-6750 1125);
PAINT RED (-6750 1125);
FORCEPROP 1 LAST TOLERANCE 1%
J 0
(-6825 1125);
DISPLAY 0.617021 (-6825 1125);
PAINT SKYBLUE (-6825 1125);
FORCEPROP 1 LAST VALUE 4.75K
J 2
(-6750 1200);
DISPLAY 0.617021 (-6750 1200);
PAINT SKYBLUE (-6750 1200);
FORCEPROP 1 LAST PACK_TYPE 0402
J 0
(-7075 1200);
DISPLAY 0.617021 (-7075 1200);
PAINT SKYBLUE (-7075 1200);
FORCEPROP 1 LAST WATTAGE 1/16W
J 2
(-6975 1125);
DISPLAY 0.617021 (-6975 1125);
PAINT SKYBLUE (-6975 1125);
FORCEPROP 1 LAST PART_NUMBER G21796-072
J 0
(-6725 1200);
DISPLAY 0.617021 (-6725 1200);
PAINT BLUE (-6725 1200);
FORCEPROP 1 LAST PATH I44
J 0
(-6950 1325);
DISPLAY 0.978723 (-6950 1325);
PAINT WHITE (-6950 1325);
DISPLAY INVISIBLE (-6950 1325);
FORCEPROP 2 LAST BOM_COST SM_CONTROLLER
J 0
(-6950 1325);
DISPLAY 1.021277 (-6950 1325);
PAINT ORANGE (-6950 1325);
DISPLAY INVISIBLE (-6950 1325);
FORCEPROP 2 LAST CDS_SEC 1
J 0
(-6950 1375);
PAINT MONO (-6950 1375);
DISPLAY INVISIBLE (-6950 1375);
FORCEPROP 2 LAST $SEC 1
J 0
(-6950 1375);
PAINT MONO (-6950 1375);
DISPLAY INVISIBLE (-6950 1375);
FORCEPROP 1 LASTPIN (-6800 1175) $PN 2
J 0
(-6838 1187);
DISPLAY 0.787234 (-6838 1187);
PAINT ORANGE (-6838 1187);
DISPLAY INVISIBLE (-6838 1187);
FORCEPROP 2 LAST ROOM BMC
J 0
(-6950 1275);
DISPLAY 1.021277 (-6950 1275);
PAINT ORANGE (-6950 1275);
DISPLAY INVISIBLE (-6950 1275);
FORCEPROP 2 LAST CDS_LIB mstr_discrete
J 0
(-6900 1175);
PAINT ORANGE (-6900 1175);
DISPLAY INVISIBLE (-6900 1175);
FORCEPROP 1 LASTPIN (-7000 1175) $PN 1
J 0
(-6988 1187);
DISPLAY 0.787234 (-6988 1187);
PAINT ORANGE (-6988 1187);
DISPLAY INVISIBLE (-6988 1187);
FORCEPROP 2 LAST CDS_LOCATION R25W112
J 0
(-6950 1225);
DISPLAY 0.617021 (-6950 1225);
PAINT AQUA (-6950 1225);
DISPLAY INVISIBLE (-6950 1225);
FORCEADD RES..1
(-6900 950);
FORCEPROP 1 LAST LOCATION R25W113
J 0
(-6950 1000);
DISPLAY 0.617021 (-6950 1000);
PAINT AQUA (-6950 1000);
FORCEPROP 1 LAST PART_NUMBER G21796-072
J 0
(-6725 975);
DISPLAY 0.617021 (-6725 975);
PAINT BLUE (-6725 975);
FORCEPROP 1 LAST TOLERANCE 1%
J 0
(-6825 900);
DISPLAY 0.617021 (-6825 900);
PAINT SKYBLUE (-6825 900);
FORCEPROP 1 LAST PACK_TYPE 0402
J 0
(-7075 975);
DISPLAY 0.617021 (-7075 975);
PAINT SKYBLUE (-7075 975);
FORCEPROP 1 LAST WATTAGE 1/16W
J 2
(-6975 900);
DISPLAY 0.617021 (-6975 900);
PAINT SKYBLUE (-6975 900);
FORCEPROP 1 LAST MATERIAL EMPTY
J 0
(-6750 900);
DISPLAY 0.617021 (-6750 900);
PAINT RED (-6750 900);
FORCEPROP 1 LAST VALUE 4.75K
J 2
(-6750 975);
DISPLAY 0.617021 (-6750 975);
PAINT SKYBLUE (-6750 975);
FORCEPROP 1 LAST PATH I45
J 0
(-6950 1100);
DISPLAY 0.978723 (-6950 1100);
PAINT WHITE (-6950 1100);
DISPLAY INVISIBLE (-6950 1100);
FORCEPROP 2 LAST BOM_COST SM_CONTROLLER
J 0
(-6950 1100);
DISPLAY 1.021277 (-6950 1100);
PAINT ORANGE (-6950 1100);
DISPLAY INVISIBLE (-6950 1100);
FORCEPROP 2 LAST CDS_SEC 1
J 0
(-6950 1150);
PAINT MONO (-6950 1150);
DISPLAY INVISIBLE (-6950 1150);
FORCEPROP 2 LAST $SEC 1
J 0
(-6950 1150);
PAINT MONO (-6950 1150);
DISPLAY INVISIBLE (-6950 1150);
FORCEPROP 1 LASTPIN (-6800 950) $PN 2
J 0
(-6838 962);
DISPLAY 0.787234 (-6838 962);
PAINT ORANGE (-6838 962);
DISPLAY INVISIBLE (-6838 962);
FORCEPROP 2 LAST ROOM BMC
J 0
(-6950 1050);
DISPLAY 1.021277 (-6950 1050);
PAINT ORANGE (-6950 1050);
DISPLAY INVISIBLE (-6950 1050);
FORCEPROP 2 LAST CDS_LIB mstr_discrete
J 0
(-6900 950);
PAINT ORANGE (-6900 950);
DISPLAY INVISIBLE (-6900 950);
FORCEPROP 1 LASTPIN (-7000 950) $PN 1
J 0
(-6988 962);
DISPLAY 0.787234 (-6988 962);
PAINT ORANGE (-6988 962);
DISPLAY INVISIBLE (-6988 962);
FORCEPROP 2 LAST CDS_LOCATION R25W113
J 0
(-6950 1000);
DISPLAY 0.617021 (-6950 1000);
PAINT AQUA (-6950 1000);
DISPLAY INVISIBLE (-6950 1000);
FORCEADD RES..1
(-6900 725);
FORCEPROP 1 LAST PACK_TYPE 0402
J 0
(-7075 750);
DISPLAY 0.617021 (-7075 750);
PAINT SKYBLUE (-7075 750);
FORCEPROP 1 LAST WATTAGE 1/16W
J 2
(-6975 675);
DISPLAY 0.617021 (-6975 675);
PAINT SKYBLUE (-6975 675);
FORCEPROP 1 LAST LOCATION R25W114
J 0
(-6950 775);
DISPLAY 0.617021 (-6950 775);
PAINT AQUA (-6950 775);
FORCEPROP 1 LAST PART_NUMBER G21796-072
J 0
(-6725 750);
DISPLAY 0.617021 (-6725 750);
PAINT BLUE (-6725 750);
FORCEPROP 1 LAST MATERIAL EMPTY
J 0
(-6750 675);
DISPLAY 0.617021 (-6750 675);
PAINT RED (-6750 675);
FORCEPROP 1 LAST TOLERANCE 1%
J 0
(-6825 675);
DISPLAY 0.617021 (-6825 675);
PAINT SKYBLUE (-6825 675);
FORCEPROP 1 LAST VALUE 4.75K
J 2
(-6750 750);
DISPLAY 0.617021 (-6750 750);
PAINT SKYBLUE (-6750 750);
FORCEPROP 1 LAST PATH I46
J 0
(-6950 875);
DISPLAY 0.978723 (-6950 875);
PAINT WHITE (-6950 875);
DISPLAY INVISIBLE (-6950 875);
FORCEPROP 2 LAST BOM_COST SM_CONTROLLER
J 0
(-6950 875);
DISPLAY 1.021277 (-6950 875);
PAINT ORANGE (-6950 875);
DISPLAY INVISIBLE (-6950 875);
FORCEPROP 2 LAST CDS_SEC 1
J 0
(-6950 925);
PAINT MONO (-6950 925);
DISPLAY INVISIBLE (-6950 925);
FORCEPROP 2 LAST $SEC 1
J 0
(-6950 925);
PAINT MONO (-6950 925);
DISPLAY INVISIBLE (-6950 925);
FORCEPROP 1 LASTPIN (-6800 725) $PN 2
J 0
(-6838 737);
DISPLAY 0.787234 (-6838 737);
PAINT ORANGE (-6838 737);
DISPLAY INVISIBLE (-6838 737);
FORCEPROP 2 LAST ROOM BMC
J 0
(-6950 825);
DISPLAY 1.021277 (-6950 825);
PAINT ORANGE (-6950 825);
DISPLAY INVISIBLE (-6950 825);
FORCEPROP 2 LAST CDS_LIB mstr_discrete
J 0
(-6900 725);
PAINT ORANGE (-6900 725);
DISPLAY INVISIBLE (-6900 725);
FORCEPROP 1 LASTPIN (-7000 725) $PN 1
J 0
(-6988 737);
DISPLAY 0.787234 (-6988 737);
PAINT ORANGE (-6988 737);
DISPLAY INVISIBLE (-6988 737);
FORCEPROP 2 LAST CDS_LOCATION R25W114
J 0
(-6950 775);
DISPLAY 0.617021 (-6950 775);
PAINT AQUA (-6950 775);
DISPLAY INVISIBLE (-6950 775);
FORCEADD RES..1
(-6875 475);
FORCEPROP 1 LAST LOCATION R25W115
J 0
(-6925 525);
DISPLAY 0.617021 (-6925 525);
PAINT AQUA (-6925 525);
FORCEPROP 1 LAST TOLERANCE 1%
J 0
(-6800 425);
DISPLAY 0.617021 (-6800 425);
PAINT SKYBLUE (-6800 425);
FORCEPROP 1 LAST MATERIAL CHIP
J 0
(-6725 425);
DISPLAY 0.617021 (-6725 425);
PAINT SKYBLUE (-6725 425);
FORCEPROP 1 LAST WATTAGE 1/16W
J 2
(-7000 425);
DISPLAY 0.617021 (-7000 425);
PAINT SKYBLUE (-7000 425);
FORCEPROP 1 LAST PART_NUMBER G21796-072
J 0
(-6700 500);
DISPLAY 0.617021 (-6700 500);
PAINT BLUE (-6700 500);
FORCEPROP 1 LAST VALUE 4.75K
J 2
(-6725 500);
DISPLAY 0.617021 (-6725 500);
PAINT SKYBLUE (-6725 500);
FORCEPROP 1 LAST PACK_TYPE 0402
J 0
(-7050 500);
DISPLAY 0.617021 (-7050 500);
PAINT SKYBLUE (-7050 500);
FORCEPROP 1 LAST PATH I47
J 0
(-6925 625);
DISPLAY 0.978723 (-6925 625);
PAINT WHITE (-6925 625);
DISPLAY INVISIBLE (-6925 625);
FORCEPROP 2 LAST ROOM BMC
J 0
(-6925 575);
DISPLAY 1.021277 (-6925 575);
PAINT ORANGE (-6925 575);
DISPLAY INVISIBLE (-6925 575);
FORCEPROP 2 LAST BOM_COST SM_CONTROLLER
J 0
(-6925 625);
DISPLAY 1.021277 (-6925 625);
PAINT ORANGE (-6925 625);
DISPLAY INVISIBLE (-6925 625);
FORCEPROP 2 LAST CDS_LIB mstr_discrete
J 0
(-6875 475);
PAINT MONO (-6875 475);
DISPLAY INVISIBLE (-6875 475);
FORCEPROP 1 LASTPIN (-6975 475) $PN 1
J 0
(-6963 487);
DISPLAY 0.787234 (-6963 487);
PAINT ORANGE (-6963 487);
DISPLAY INVISIBLE (-6963 487);
FORCEPROP 1 LASTPIN (-6775 475) $PN 2
J 0
(-6813 487);
DISPLAY 0.787234 (-6813 487);
PAINT ORANGE (-6813 487);
DISPLAY INVISIBLE (-6813 487);
FORCEADD RES..2
R 1
(-6825 225);
FORCEPROP 1 LASTPIN (-6725 225) $PN 2
R 1
J 0
(-6735 230);
DISPLAY 0.617021 (-6735 230);
PAINT ORANGE (-6735 230);
FORCEPROP 1 LAST PART_NUMBER G21796-027
J 0
(-6775 165);
DISPLAY 0.617021 (-6775 165);
PAINT BLUE (-6775 165);
FORCEPROP 1 LAST PACK_TYPE 0402
R 1
J 0
(-6650 265);
DISPLAY 0.617021 (-6650 265);
PAINT SKYBLUE (-6650 265);
FORCEPROP 1 LAST MATERIAL CHIP
R 1
J 0
(-6750 265);
DISPLAY 0.617021 (-6750 265);
PAINT SKYBLUE (-6750 265);
FORCEPROP 1 LAST WATTAGE 1/16W
R 1
J 0
(-6800 265);
DISPLAY 0.617021 (-6800 265);
PAINT SKYBLUE (-6800 265);
FORCEPROP 1 LAST VALUE 3.32K
R 1
J 0
(-6900 270);
DISPLAY 0.617021 (-6900 270);
PAINT SKYBLUE (-6900 270);
FORCEPROP 1 LASTPIN (-6925 225) $PN 1
R 1
J 0
(-6887 230);
DISPLAY 0.617021 (-6887 230);
PAINT ORANGE (-6887 230);
FORCEPROP 1 LAST TOLERANCE 1%
R 1
J 0
(-6850 270);
DISPLAY 0.617021 (-6850 270);
PAINT SKYBLUE (-6850 270);
FORCEPROP 1 LAST LOCATION R25W116
R 1
J 0
(-6950 270);
DISPLAY 0.617021 (-6950 270);
PAINT AQUA (-6950 270);
FORCEPROP 1 LAST PATH I48
R 1
J 0
(-7000 275);
DISPLAY 0.978723 (-7000 275);
PAINT WHITE (-7000 275);
DISPLAY INVISIBLE (-7000 275);
FORCEPROP 2 LAST SEC 1
R 1
J 0
(-7050 275);
PAINT MONO (-7050 275);
DISPLAY INVISIBLE (-7050 275);
FORCEPROP 2 LAST BOM_COST NT_GBE_BASE
R 1
J 0
(-7050 275);
DISPLAY 1.021277 (-7050 275);
PAINT ORANGE (-7050 275);
DISPLAY INVISIBLE (-7050 275);
FORCEPROP 2 LAST SEC_TYPE 0402
R 1
J 0
(-7050 275);
DISPLAY 1.021277 (-7050 275);
PAINT ORANGE (-7050 275);
DISPLAY INVISIBLE (-7050 275);
FORCEPROP 2 LAST ROOM NIC_SPRV
R 1
J 0
(-7000 275);
DISPLAY 1.021277 (-7000 275);
PAINT ORANGE (-7000 275);
DISPLAY INVISIBLE (-7000 275);
FORCEPROP 2 LAST CDS_LIB mstr_discrete
R 1
J 0
(-6825 225);
PAINT ORANGE (-6825 225);
DISPLAY INVISIBLE (-6825 225);
FORCEPROP 0 LAST CDS_SEC 1
R 1
J 0
(-7000 275);
PAINT MONO (-7000 275);
DISPLAY INVISIBLE (-7000 275);
FORCEPROP 2 LAST CDS_LOCATION R25W116
R 1
J 0
(-6950 270);
DISPLAY 0.617021 (-6950 270);
PAINT AQUA (-6950 270);
DISPLAY INVISIBLE (-6950 270);
FORCEADD OFFPAGE..2
(-5650 4425);
FORCEPROP 2 LAST $XR2 246 
J 0
(-5286 4425);
DISPLAY 0.638298 (-5286 4425);
PAINT MONO (-5286 4425);
FORCEPROP 2 LAST $XR0 146 
J 0
(-5386 4425);
DISPLAY 0.638298 (-5386 4425);
PAINT MONO (-5386 4425);
FORCEPROP 2 LAST $XR1 162 
J 0
(-5461 4425);
DISPLAY 0.638298 (-5461 4425);
PAINT MONO (-5461 4425);
FORCEPROP 2 LAST PATH I5
J 0
(-5275 4475);
DISPLAY 1.021277 (-5275 4475);
PAINT ORANGE (-5275 4475);
DISPLAY INVISIBLE (-5275 4475);
FORCEPROP 2 LAST CDS_LIB mstr_standard
J 0
(-5650 4425);
PAINT ORANGE (-5650 4425);
DISPLAY INVISIBLE (-5650 4425);
FORCEPROP 1 LAST OFFPAGE TRUE
J 0
(-5325 4300);
DISPLAY 0.872340 (-5325 4300);
PAINT GREEN (-5325 4300);
DISPLAY INVISIBLE (-5325 4300);
FORCEPROP 1 LAST COMMENT_BODY TRUE
J 0
(-5695 4330);
DISPLAY 0.872340 (-5695 4330);
PAINT GREEN (-5695 4330);
DISPLAY INVISIBLE (-5695 4330);
FORCEADD OFFPAGE..4
(-5650 4275);
FORCEPROP 2 LAST $XR1 246 
J 0
(-5289 4275);
DISPLAY 0.638298 (-5289 4275);
PAINT MONO (-5289 4275);
FORCEPROP 2 LAST $XR0 162 
J 0
(-5389 4275);
DISPLAY 0.638298 (-5389 4275);
PAINT MONO (-5389 4275);
FORCEPROP 2 LAST $XR2 146 
J 0
(-5464 4275);
DISPLAY 0.638298 (-5464 4275);
PAINT MONO (-5464 4275);
FORCEPROP 2 LAST PATH I6
J 0
(-5275 4325);
DISPLAY 1.021277 (-5275 4325);
PAINT ORANGE (-5275 4325);
DISPLAY INVISIBLE (-5275 4325);
FORCEPROP 2 LAST CDS_LIB mstr_standard
J 0
(-5650 4275);
PAINT ORANGE (-5650 4275);
DISPLAY INVISIBLE (-5650 4275);
FORCEPROP 1 LAST OFFPAGE TRUE
J 0
(-5325 4150);
DISPLAY 0.872340 (-5325 4150);
PAINT GREEN (-5325 4150);
DISPLAY INVISIBLE (-5325 4150);
FORCEPROP 1 LAST COMMENT_BODY TRUE
J 0
(-5675 4175);
DISPLAY 0.872340 (-5675 4175);
PAINT GREEN (-5675 4175);
DISPLAY INVISIBLE (-5675 4175);
FORCEADD OFFPAGE..2
(-5650 4000);
FORCEPROP 2 LAST $XR0 152 
J 0
(-5361 4000);
DISPLAY 0.638298 (-5361 4000);
PAINT MONO (-5361 4000);
FORCEPROP 2 LAST $XR1 146 
J 0
(-5461 4000);
DISPLAY 0.638298 (-5461 4000);
PAINT MONO (-5461 4000);
FORCEPROP 2 LAST PATH I7
J 0
(-5350 4050);
DISPLAY 1.021277 (-5350 4050);
PAINT ORANGE (-5350 4050);
DISPLAY INVISIBLE (-5350 4050);
FORCEPROP 2 LAST CDS_LIB mstr_standard
J 0
(-5650 4000);
PAINT ORANGE (-5650 4000);
DISPLAY INVISIBLE (-5650 4000);
FORCEPROP 1 LAST OFFPAGE TRUE
J 0
(-5325 3875);
DISPLAY 0.872340 (-5325 3875);
PAINT GREEN (-5325 3875);
DISPLAY INVISIBLE (-5325 3875);
FORCEPROP 1 LAST COMMENT_BODY TRUE
J 0
(-5695 3905);
DISPLAY 0.872340 (-5695 3905);
PAINT GREEN (-5695 3905);
DISPLAY INVISIBLE (-5695 3905);
FORCEADD OFFPAGE..2
(-5650 3825);
FORCEPROP 2 LAST $XR3 175 
J 0
(-5461 3825);
DISPLAY 0.638298 (-5461 3825);
PAINT MONO (-5461 3825);
FORCEPROP 2 LAST $XR2 146 
J 0
(-5461 3825);
DISPLAY 0.638298 (-5461 3825);
PAINT MONO (-5461 3825);
FORCEPROP 2 LAST $XR1 133 
J 0
(-5461 3825);
DISPLAY 0.638298 (-5461 3825);
PAINT MONO (-5461 3825);
FORCEPROP 2 LAST $XR0 120 
J 0
(-5461 3825);
DISPLAY 0.638298 (-5461 3825);
PAINT MONO (-5461 3825);
FORCEPROP 2 LAST PATH I8
J 0
(-5475 3900);
DISPLAY 1.021277 (-5475 3900);
PAINT ORANGE (-5475 3900);
DISPLAY INVISIBLE (-5475 3900);
FORCEPROP 2 LAST $XRERR ?
J 0
(-5461 3825);
DISPLAY 0.638298 (-5461 3825);
PAINT MONO (-5461 3825);
DISPLAY INVISIBLE (-5461 3825);
FORCEPROP 2 LAST $XRERR ?
J 0
(-5461 3825);
DISPLAY 0.638298 (-5461 3825);
PAINT MONO (-5461 3825);
DISPLAY INVISIBLE (-5461 3825);
FORCEPROP 2 LAST $XRERR ?
J 0
(-5461 3825);
DISPLAY 0.638298 (-5461 3825);
PAINT MONO (-5461 3825);
DISPLAY INVISIBLE (-5461 3825);
FORCEPROP 2 LAST $XRERR ?
J 0
(-5461 3825);
DISPLAY 0.638298 (-5461 3825);
PAINT MONO (-5461 3825);
DISPLAY INVISIBLE (-5461 3825);
FORCEPROP 2 LAST $XRERR ?
J 0
(-5461 3825);
DISPLAY 0.638298 (-5461 3825);
PAINT MONO (-5461 3825);
DISPLAY INVISIBLE (-5461 3825);
FORCEPROP 2 LAST CDS_LIB mstr_standard
J 0
(-5650 3825);
PAINT MONO (-5650 3825);
DISPLAY INVISIBLE (-5650 3825);
FORCEPROP 2 LAST $XRERR ?
J 0
(-5461 3825);
DISPLAY 0.638298 (-5461 3825);
PAINT MONO (-5461 3825);
DISPLAY INVISIBLE (-5461 3825);
FORCEPROP 1 LAST OFFPAGE TRUE
J 0
(-5325 3700);
DISPLAY 0.872340 (-5325 3700);
PAINT GREEN (-5325 3700);
DISPLAY INVISIBLE (-5325 3700);
FORCEPROP 1 LAST COMMENT_BODY TRUE
J 0
(-5695 3730);
DISPLAY 0.872340 (-5695 3730);
PAINT GREEN (-5695 3730);
DISPLAY INVISIBLE (-5695 3730);
FORCEPROP 2 LAST $XRERR ?
J 0
(-5461 3825);
DISPLAY 0.638298 (-5461 3825);
PAINT MONO (-5461 3825);
DISPLAY INVISIBLE (-5461 3825);
FORCEPROP 2 LAST $XRERR ?
J 0
(-5461 3825);
DISPLAY 0.638298 (-5461 3825);
PAINT MONO (-5461 3825);
DISPLAY INVISIBLE (-5461 3825);
FORCEPROP 2 LAST $XRERR ?
J 0
(-5461 3825);
DISPLAY 0.638298 (-5461 3825);
PAINT MONO (-5461 3825);
DISPLAY INVISIBLE (-5461 3825);
FORCEPROP 2 LAST $XRERR ?
J 0
(-5461 3825);
DISPLAY 0.638298 (-5461 3825);
PAINT MONO (-5461 3825);
DISPLAY INVISIBLE (-5461 3825);
FORCEPROP 2 LAST $XRERR ?
J 0
(-5461 3825);
DISPLAY 0.638298 (-5461 3825);
PAINT MONO (-5461 3825);
DISPLAY INVISIBLE (-5461 3825);
FORCEPROP 2 LAST $XRERR ?
J 0
(-5461 3825);
DISPLAY 0.638298 (-5461 3825);
PAINT MONO (-5461 3825);
DISPLAY INVISIBLE (-5461 3825);
FORCEADD RES..1
(-6900 4675);
FORCEPROP 1 LAST MATERIAL CHIP
J 0
(-6750 4625);
DISPLAY 0.617021 (-6750 4625);
PAINT SKYBLUE (-6750 4625);
FORCEPROP 1 LAST PART_NUMBER G21796-072
J 0
(-6725 4700);
DISPLAY 0.617021 (-6725 4700);
PAINT BLUE (-6725 4700);
FORCEPROP 1 LAST LOCATION R25W94
J 0
(-6950 4725);
DISPLAY 0.617021 (-6950 4725);
PAINT AQUA (-6950 4725);
FORCEPROP 1 LAST PACK_TYPE 0402
J 0
(-7075 4700);
DISPLAY 0.617021 (-7075 4700);
PAINT SKYBLUE (-7075 4700);
FORCEPROP 1 LASTPIN (-7000 4675) $PN 1
J 0
(-6988 4687);
DISPLAY 0.617021 (-6988 4687);
PAINT ORANGE (-6988 4687);
FORCEPROP 1 LAST VALUE 4.75K
J 2
(-6750 4700);
DISPLAY 0.617021 (-6750 4700);
PAINT SKYBLUE (-6750 4700);
FORCEPROP 1 LAST TOLERANCE 1%
J 0
(-6825 4625);
DISPLAY 0.617021 (-6825 4625);
PAINT SKYBLUE (-6825 4625);
FORCEPROP 1 LASTPIN (-6800 4675) $PN 2
J 0
(-6838 4687);
DISPLAY 0.617021 (-6838 4687);
PAINT ORANGE (-6838 4687);
FORCEPROP 1 LAST WATTAGE 1/16W
J 2
(-6975 4625);
DISPLAY 0.617021 (-6975 4625);
PAINT SKYBLUE (-6975 4625);
FORCEPROP 1 LAST PATH I9
J 0
(-6950 4825);
DISPLAY 0.978723 (-6950 4825);
PAINT WHITE (-6950 4825);
DISPLAY INVISIBLE (-6950 4825);
FORCEPROP 0 LAST CDS_SEC 1
J 0
(-6950 4775);
PAINT MONO (-6950 4775);
DISPLAY INVISIBLE (-6950 4775);
FORCEPROP 2 LAST CDS_LIB mstr_discrete
J 0
(-6900 4675);
PAINT ORANGE (-6900 4675);
DISPLAY INVISIBLE (-6900 4675);
FORCEPROP 2 LAST ROOM BMC
J 0
(-6950 4775);
DISPLAY 1.021277 (-6950 4775);
PAINT ORANGE (-6950 4775);
DISPLAY INVISIBLE (-6950 4775);
FORCEPROP 2 LAST BOM_COST SM_CONTROLLER
J 0
(-6950 4825);
DISPLAY 1.021277 (-6950 4825);
PAINT ORANGE (-6950 4825);
DISPLAY INVISIBLE (-6950 4825);
FORCEPROP 2 LAST SEC 1
J 0
(-6950 4875);
DISPLAY 0.680851 (-6950 4875);
PAINT MONO (-6950 4875);
DISPLAY INVISIBLE (-6950 4875);
FORCEPROP 2 LAST SEC_TYPE 0402
J 0
(-6950 4875);
DISPLAY 1.021277 (-6950 4875);
PAINT ORANGE (-6950 4875);
DISPLAY INVISIBLE (-6950 4875);
FORCEPROP 2 LAST CDS_LOCATION R25W94
J 0
(-6950 4725);
DISPLAY 0.617021 (-6950 4725);
PAINT AQUA (-6950 4725);
DISPLAY INVISIBLE (-6950 4725);
FORCEADD DNS..2
(-6895 2495);
PAINT RED (-6895 2495);
FORCEPROP 2 LAST CDS_LIB mstr_misc
J 0
(-6895 2495);
PAINT ORANGE (-6895 2495);
DISPLAY INVISIBLE (-6895 2495);
FORCEPROP 1 LAST COMMENT_BODY TRUE
R 1
J 0
(-6820 2270);
DISPLAY 0.872340 (-6820 2270);
PAINT GREEN (-6820 2270);
DISPLAY INVISIBLE (-6820 2270);
FORCEADD DNS..2
(-6895 2720);
PAINT RED (-6895 2720);
FORCEPROP 2 LAST CDS_LIB mstr_misc
J 0
(-6895 2720);
PAINT ORANGE (-6895 2720);
DISPLAY INVISIBLE (-6895 2720);
FORCEPROP 1 LAST COMMENT_BODY TRUE
R 1
J 0
(-6820 2495);
DISPLAY 0.872340 (-6820 2495);
PAINT GREEN (-6820 2495);
DISPLAY INVISIBLE (-6820 2495);
FORCEADD DNS..2
(-6895 3170);
PAINT RED (-6895 3170);
FORCEPROP 2 LAST CDS_LIB mstr_misc
J 0
(-6895 3170);
PAINT ORANGE (-6895 3170);
DISPLAY INVISIBLE (-6895 3170);
FORCEPROP 1 LAST COMMENT_BODY TRUE
R 1
J 0
(-6820 2945);
DISPLAY 0.872340 (-6820 2945);
PAINT GREEN (-6820 2945);
DISPLAY INVISIBLE (-6820 2945);
FORCEADD DNS..2
(-6895 2945);
PAINT RED (-6895 2945);
FORCEPROP 2 LAST CDS_LIB mstr_misc
J 0
(-6895 2945);
PAINT ORANGE (-6895 2945);
DISPLAY INVISIBLE (-6895 2945);
FORCEPROP 1 LAST COMMENT_BODY TRUE
R 1
J 0
(-6820 2720);
DISPLAY 0.872340 (-6820 2720);
PAINT GREEN (-6820 2720);
DISPLAY INVISIBLE (-6820 2720);
FORCEADD DNS..2
(-6895 945);
PAINT RED (-6895 945);
FORCEPROP 2 LAST CDS_LIB mstr_misc
J 0
(-6895 945);
PAINT ORANGE (-6895 945);
DISPLAY INVISIBLE (-6895 945);
FORCEPROP 1 LAST COMMENT_BODY TRUE
R 1
J 0
(-6820 720);
DISPLAY 0.872340 (-6820 720);
PAINT GREEN (-6820 720);
DISPLAY INVISIBLE (-6820 720);
FORCEADD DNS..2
(-6895 3470);
PAINT RED (-6895 3470);
FORCEPROP 2 LAST CDS_LIB mstr_misc
J 0
(-6895 3470);
PAINT ORANGE (-6895 3470);
DISPLAY INVISIBLE (-6895 3470);
FORCEPROP 1 LAST COMMENT_BODY TRUE
R 1
J 0
(-6820 3245);
DISPLAY 0.872340 (-6820 3245);
PAINT GREEN (-6820 3245);
DISPLAY INVISIBLE (-6820 3245);
FORCEADD DNS..2
(-6895 720);
PAINT RED (-6895 720);
FORCEPROP 2 LAST CDS_LIB mstr_misc
J 0
(-6895 720);
PAINT ORANGE (-6895 720);
DISPLAY INVISIBLE (-6895 720);
FORCEPROP 1 LAST COMMENT_BODY TRUE
R 1
J 0
(-6820 495);
DISPLAY 0.872340 (-6820 495);
PAINT GREEN (-6820 495);
DISPLAY INVISIBLE (-6820 495);
FORCEADD DNS..2
(-6920 3820);
PAINT RED (-6920 3820);
FORCEPROP 2 LAST CDS_LIB mstr_misc
J 0
(-6920 3820);
PAINT ORANGE (-6920 3820);
DISPLAY INVISIBLE (-6920 3820);
FORCEPROP 1 LAST COMMENT_BODY TRUE
R 1
J 0
(-6845 3595);
DISPLAY 0.872340 (-6845 3595);
PAINT GREEN (-6845 3595);
DISPLAY INVISIBLE (-6845 3595);
FORCEADD DNS..2
(-6895 2270);
PAINT RED (-6895 2270);
FORCEPROP 2 LAST CDS_LIB mstr_misc
J 0
(-6895 2270);
PAINT ORANGE (-6895 2270);
DISPLAY INVISIBLE (-6895 2270);
FORCEPROP 1 LAST COMMENT_BODY TRUE
R 1
J 0
(-6820 2045);
DISPLAY 0.872340 (-6820 2045);
PAINT GREEN (-6820 2045);
DISPLAY INVISIBLE (-6820 2045);
FORCEADD DNS..2
(-6895 1170);
PAINT RED (-6895 1170);
FORCEPROP 2 LAST CDS_LIB mstr_misc
J 0
(-6895 1170);
PAINT ORANGE (-6895 1170);
DISPLAY INVISIBLE (-6895 1170);
FORCEPROP 1 LAST COMMENT_BODY TRUE
R 1
J 0
(-6820 945);
DISPLAY 0.872340 (-6820 945);
PAINT GREEN (-6820 945);
DISPLAY INVISIBLE (-6820 945);
FORCEADD DNS..2
(-6870 1845);
PAINT RED (-6870 1845);
FORCEPROP 2 LAST CDS_LIB mstr_misc
J 0
(-6870 1845);
PAINT ORANGE (-6870 1845);
DISPLAY INVISIBLE (-6870 1845);
FORCEPROP 1 LAST COMMENT_BODY TRUE
R 1
J 0
(-6795 1620);
DISPLAY 0.872340 (-6795 1620);
PAINT GREEN (-6795 1620);
DISPLAY INVISIBLE (-6795 1620);
FORCEADD DNS..2
(-6895 1395);
PAINT RED (-6895 1395);
FORCEPROP 2 LAST CDS_LIB mstr_misc
J 0
(-6895 1395);
PAINT ORANGE (-6895 1395);
DISPLAY INVISIBLE (-6895 1395);
FORCEPROP 1 LAST COMMENT_BODY TRUE
R 1
J 0
(-6820 1170);
DISPLAY 0.872340 (-6820 1170);
PAINT GREEN (-6820 1170);
DISPLAY INVISIBLE (-6820 1170);
FORCEADD DNS..2
(-6895 4270);
PAINT RED (-6895 4270);
FORCEPROP 2 LAST CDS_LIB mstr_misc
J 0
(-6895 4270);
PAINT ORANGE (-6895 4270);
DISPLAY INVISIBLE (-6895 4270);
FORCEPROP 1 LAST COMMENT_BODY TRUE
R 1
J 0
(-6820 4045);
DISPLAY 0.872340 (-6820 4045);
PAINT GREEN (-6820 4045);
DISPLAY INVISIBLE (-6820 4045);
FORCEADD INTEL_CORP_BPAGE..1
(0 0);
FORCEPROP 1 LAST CDS_CON_LAST_MODIFIED Tue Dec 01 11:52:07 2015
J 0
(-1425 325);
DISPLAY 1.361702 (-1425 325);
PAINT GREEN (-1425 325);
DISPLAY INVISIBLE (-1425 325);
FORCEPROP 1 LAST CUSTOM_TXT_CDS <CURRENT_DESIGN_SHEET> OF <TOTAL_DESIGN_SHEETS>
J 0
(-500 25);
PAINT GREEN (-500 25);
FORCEPROP 1 LAST CUSTOM_TXT_CDS <CON_LAST_MODIFIED>
J 0
(-1925 350);
PAINT GREEN (-1925 350);
FORCEPROP 2 LAST CUSTOM_TXT_CDS <XR_PAGE_TITLE>
J 0
(-7890 5250);
DISPLAY 0.638298 (-7890 5250);
PAINT PINK (-7890 5250);
DISPLAY INVISIBLE (-7890 5250);
FORCEPROP 1 LAST SCH_TITLE BMC STRAPS
J 0
(-7950 50);
DISPLAY 1.212766 (-7950 50);
PAINT ORANGE (-7950 50);
FORCEPROP 1 LAST SCH_ADDRESS1 2200 Mission College Blvd.
J 0
(-3975 125);
DISPLAY 0.617021 (-3975 125);
PAINT GREEN (-3975 125);
FORCEPROP 1 LAST SCH_NUMBER H4694802
J 0
(-1300 150);
DISPLAY 1.212766 (-1300 150);
PAINT YELLOW (-1300 150);
FORCEPROP 1 LAST SCH_ADDRESS2 P.O. BOX 58119
J 0
(-3975 75);
DISPLAY 0.617021 (-3975 75);
PAINT GREEN (-3975 75);
FORCEPROP 1 LAST SCH_ADDRESS3 Santa Clara, CA 95052-8119
J 0
(-3975 25);
DISPLAY 0.617021 (-3975 25);
PAINT GREEN (-3975 25);
FORCEPROP 1 LAST SCH_REV 2.420
J 0
(-250 150);
DISPLAY 0.978723 (-250 150);
PAINT YELLOW (-250 150);
FORCEPROP 1 LAST SCH_DEPT BESD
J 1
(-4450 100);
DISPLAY 1.212766 (-4450 100);
PAINT YELLOW (-4450 100);
FORCEPROP 2 LAST PAGE_BORDER TRUE
J 0
(-7890 5250);
DISPLAY 0.851064 (-7890 5250);
PAINT PINK (-7890 5250);
DISPLAY INVISIBLE (-7890 5250);
FORCEPROP 2 LAST CDS_LIB mstr_symbols
J 0
(0 0);
DISPLAY 1.361702 (0 0);
PAINT ORANGE (0 0);
DISPLAY INVISIBLE (0 0);
FORCEPROP 1 LAST COMMENT_BODY TRUE
J 0
(12 12);
DISPLAY 0.617021 (12 12);
PAINT GREEN (12 12);
DISPLAY INVISIBLE (12 12);
FORCEPROP 2 LAST CDS_XR_PAGE_TITLE CR-151 : @BASEBOARD_FAB2_LIB.BASEBOARD_FAB2(SCH_1):PAGE151
J 0
(-7890 5250);
DISPLAY 0.638298 (-7890 5250);
PAINT PINK (-7890 5250);
DISPLAY INVISIBLE (-7890 5250);
WIRE 16 -1 (-6925 225)(-7325 225);
WIRE 16 -1 (-7325 225)(-7325 175);
WIRE 16 -1 (-6975 475)(-7325 475);
WIRE 16 -1 (-7325 725)(-7325 475);
WIRE 16 -1 (-7325 725)(-7000 725);
WIRE 16 -1 (-7325 725)(-7325 950);
WIRE 16 -1 (-7325 950)(-7000 950);
WIRE 16 -1 (-7325 950)(-7325 1175);
WIRE 16 -1 (-7325 1175)(-7000 1175);
WIRE 16 -1 (-7325 1400)(-7325 1175);
WIRE 16 -1 (-7325 1400)(-7000 1400);
WIRE 16 -1 (-7325 1400)(-7325 1675);
WIRE 16 -1 (-6950 1675)(-7325 1675);
WIRE 16 -1 (-7325 1850)(-7325 1675);
WIRE 16 -1 (-7325 1850)(-7325 2075);
WIRE 16 -1 (-7325 1850)(-6975 1850);
WIRE 16 -1 (-6975 2075)(-7325 2075);
WIRE 16 -1 (-7325 2275)(-7325 2075);
WIRE 16 -1 (-7325 2275)(-7000 2275);
WIRE 16 -1 (-7325 2275)(-7325 2500);
WIRE 16 -1 (-7325 2500)(-7000 2500);
WIRE 16 -1 (-7325 2500)(-7325 2725);
WIRE 16 -1 (-7325 2725)(-7000 2725);
WIRE 16 -1 (-7325 2950)(-7325 2725);
WIRE 16 -1 (-7325 2950)(-7000 2950);
WIRE 16 -1 (-7325 2950)(-7325 3175);
WIRE 16 -1 (-7325 3175)(-7000 3175);
WIRE 16 -1 (-7325 3325)(-7325 3175);
WIRE 16 -1 (-7000 3325)(-7325 3325);
WIRE 16 -1 (-7325 3475)(-7325 3325);
WIRE 16 -1 (-7325 3475)(-7000 3475);
WIRE 16 -1 (-7325 3475)(-7325 3625);
WIRE 16 -1 (-7000 3625)(-7325 3625);
WIRE 16 -1 (-7325 3625)(-7325 3825);
WIRE 16 -1 (-7325 3825)(-7025 3825);
WIRE 16 -1 (-7325 3825)(-7325 4000);
WIRE 16 -1 (-7000 4000)(-7325 4000);
WIRE 16 -1 (-7325 4000)(-7325 4275);
WIRE 16 -1 (-7325 4275)(-7000 4275);
WIRE 16 -1 (-7325 4275)(-7325 4425);
WIRE 16 -1 (-7000 4425)(-7325 4425);
WIRE 16 -1 (-7325 4425)(-7325 4550);
WIRE 16 -1 (-7000 4550)(-7325 4550);
WIRE 16 -1 (-7325 4550)(-7325 4675);
WIRE 16 -1 (-7000 4675)(-7325 4675);
WIRE 16 -1 (-7325 4800)(-7325 4675);
WIRE 16 -1 (-6800 4425)(-5700 4425);
FORCEPROP 2 LAST SIG_NAME SPI_BMC_BT_DO
J 0
(-6325 4435);
DISPLAY 0.617021 (-6325 4435);
PAINT ORANGE (-6325 4435);
WIRE 16 -1 (-6800 3625)(-5675 3625);
FORCEPROP 2 LAST SIG_NAME GPIOS7
J 0
(-6300 3635);
DISPLAY 0.617021 (-6300 3635);
PAINT ORANGE (-6300 3635);
WIRE 16 -1 (-6800 4000)(-5700 4000);
FORCEPROP 2 LAST SIG_NAME H_CPU0_MEMDEF_MEMHOT_LVT3_BMC_N
J 0
(-6475 4010);
DISPLAY 0.617021 (-6475 4010);
PAINT ORANGE (-6475 4010);
WIRE 16 -1 (-5650 3175)(-6800 3175);
FORCEPROP 2 LAST SIG_NAME H_CPU0_MEMABC_MEMHOT_LVT3_BMC_N
J 0
(-6475 3185);
DISPLAY 0.680851 (-6475 3185);
PAINT ORANGE (-6475 3185);
WIRE 16 -1 (-6800 3325)(-5650 3325);
FORCEPROP 2 LAST SIG_NAME FM_CPU0_THERMTRIP_LATCH_LVT3_N
J 0
(-6450 3335);
DISPLAY 0.680851 (-6450 3335);
PAINT ORANGE (-6450 3335);
WIRE 16 -1 (-5650 3475)(-6800 3475);
FORCEPROP 2 LAST SIG_NAME HSC_SMBUS_SWITCH_EN
J 0
(-6460 3485);
DISPLAY 0.680851 (-6460 3485);
PAINT ORANGE (-6460 3485);
WIRE 17 2175 (-4375 2475)(-2225 2475);
WIRE 17 2175 (-4400 4925)(-225 4925);
WIRE 17 2175 (-4400 4925)(-4400 650);
WIRE 17 2175 (-225 650)(-225 4925);
WIRE 17 2175 (-4400 650)(-225 650);
WIRE 16 -1 (-5975 2500)(-6800 2500);
FORCEPROP 2 LAST SIG_NAME RMII_BMC_OCP_TXEN
J 2
(-5950 2510);
DISPLAY 0.617021 (-5950 2510);
PAINT ORANGE (-5950 2510);
WIRE 16 -1 (-5975 2725)(-6800 2725);
FORCEPROP 2 LAST SIG_NAME JTAG_BMC_TRST_N
J 2
(-6025 2735);
DISPLAY 0.617021 (-6025 2735);
PAINT ORANGE (-6025 2735);
WIRE 16 -1 (-6800 2950)(-5975 2950);
FORCEPROP 2 LAST SIG_NAME FM_CPU1_PROC_ID0
J 0
(-6450 2960);
DISPLAY 0.617021 (-6450 2960);
PAINT ORANGE (-6450 2960);
WIRE 17 2175 (-4375 1625)(-2225 1625);
WIRE 16 -1 (-6775 475)(-5950 475);
FORCEPROP 2 LAST SIG_NAME TP_RGMII1TXD3_GPIOT5
J 2
(-5975 485);
DISPLAY 0.617021 (-5975 485);
PAINT ORANGE (-5975 485);
WIRE 16 -1 (-5700 3825)(-6825 3825);
FORCEPROP 2 LAST SIG_NAME FP_PWR_ID_LED_N
J 0
(-6410 3835);
DISPLAY 0.680851 (-6410 3835);
PAINT ORANGE (-6410 3835);
WIRE 16 -1 (-6800 2275)(-5975 2275);
FORCEPROP 2 LAST SIG_NAME RMII_BMC_OCP_TXD0_R
J 0
(-6410 2285);
DISPLAY 0.617021 (-6410 2285);
PAINT ORANGE (-6410 2285);
WIRE 16 -1 (-5950 2075)(-6775 2075);
FORCEPROP 2 LAST SIG_NAME RMII_BMC_OCP_TXD1_R
J 0
(-6410 2085);
DISPLAY 0.617021 (-6410 2085);
PAINT ORANGE (-6410 2085);
WIRE 17 2175 (-4375 3075)(-2225 3075);
WIRE 16 -1 (-5950 1850)(-6775 1850);
FORCEPROP 2 LAST SIG_NAME TP_RGMII2TXD3_GPIOT5
J 2
(-5975 1860);
DISPLAY 0.617021 (-5975 1860);
PAINT ORANGE (-5975 1860);
WIRE 16 -1 (-6750 1675)(-5925 1675);
FORCEPROP 2 LAST SIG_NAME TP_RGMII2TXD2_GPIOT4
J 2
(-5975 1685);
DISPLAY 0.617021 (-5975 1685);
PAINT ORANGE (-5975 1685);
WIRE 17 2175 (-4375 1900)(-2225 1900);
WIRE 16 -1 (-6725 225)(-5950 225);
FORCEPROP 2 LAST SIG_NAME UART_BMC_TXD5
J 0
(-6510 235);
DISPLAY 0.617021 (-6510 235);
PAINT ORANGE (-6510 235);
WIRE 16 -1 (-5975 950)(-6800 950);
FORCEPROP 2 LAST SIG_NAME RMII_BMC_PCH_SPRNGVLLE_TXD1_R
J 0
(-6460 985);
DISPLAY 0.617021 (-6460 985);
PAINT ORANGE (-6460 985);
WIRE 17 2175 (-2175 700)(-2175 4900);
WIRE 16 -1 (-5900 1400)(-6800 1400);
FORCEPROP 2 LAST SIG_NAME RMII_BMC_PCH_SPRNGVLLE_TXEN
J 2
(-5900 1410);
DISPLAY 0.617021 (-5900 1410);
PAINT ORANGE (-5900 1410);
WIRE 16 -1 (-5975 725)(-6800 725);
FORCEPROP 2 LAST SIG_NAME TP_RGMII1TXD2_GPIOT4
J 2
(-5975 735);
DISPLAY 0.617021 (-5975 735);
PAINT ORANGE (-5975 735);
WIRE 16 -1 (-5700 4275)(-6800 4275);
FORCEPROP 2 LAST SIG_NAME SPI_BMC_BT_DI
J 0
(-6325 4285);
DISPLAY 0.617021 (-6325 4285);
PAINT ORANGE (-6325 4285);
WIRE 17 2175 (-4375 2750)(-2225 2750);
WIRE 17 2175 (-4375 3350)(-2225 3350);
WIRE 17 2175 (-4375 2200)(-2225 2200);
WIRE 17 2175 (-4350 1075)(-2200 1075);
WIRE 17 2175 (-4375 1325)(-2225 1325);
WIRE 17 2175 (-4375 4200)(-2225 4200);
WIRE 17 2175 (-4375 3950)(-2225 3950);
WIRE 17 2175 (-4375 3725)(-2225 3725);
WIRE 17 2175 (-4375 4450)(-2225 4450);
WIRE 17 2175 (-2125 4450)(-325 4450);
WIRE 17 2175 (-2150 3750)(-350 3750);
WIRE 17 2175 (-2125 2750)(-325 2750);
WIRE 17 2175 (-2125 3375)(-325 3375);
WIRE 17 2175 (-2125 3075)(-325 3075);
WIRE 17 2175 (-2150 3950)(-350 3950);
WIRE 17 2175 (-2125 4200)(-325 4200);
WIRE 16 -1 (-6800 4675)(-5700 4675);
FORCEPROP 2 LAST SIG_NAME SPI_BMC_BT_CS_N
J 0
(-6335 4685);
DISPLAY 0.617021 (-6335 4685);
PAINT ORANGE (-6335 4685);
WIRE 16 -1 (-6800 4550)(-5700 4550);
FORCEPROP 2 LAST SIG_NAME SPI_BMC_BT_CLK
J 0
(-6325 4560);
DISPLAY 0.617021 (-6325 4560);
PAINT ORANGE (-6325 4560);
WIRE 16 -1 (-5900 1175)(-6800 1175);
FORCEPROP 2 LAST SIG_NAME RMII_BMC_PCH_SPRNGVLLE_TXD0_R
J 0
(-6435 1185);
DISPLAY 0.617021 (-6435 1185);
PAINT ORANGE (-6435 1185);
WIRE 17 2175 (-2125 2475)(-325 2475);
DOT 1 (-7325 4675);
DOT 1 (-7325 4550);
DOT 1 (-7325 4425);
DOT 1 (-7325 4275);
DOT 1 (-7325 4000);
DOT 1 (-7325 3625);
DOT 1 (-7325 3825);
DOT 1 (-7325 3475);
DOT 1 (-7325 3175);
DOT 1 (-7325 3325);
DOT 1 (-7325 2950);
DOT 1 (-7325 2725);
DOT 1 (-7325 2500);
DOT 1 (-7325 2275);
DOT 1 (-7325 2075);
DOT 1 (-7325 1850);
DOT 1 (-7325 1675);
DOT 1 (-7325 1175);
DOT 1 (-7325 1400);
DOT 1 (-7325 725);
DOT 1 (-7325 950);
FORCENOTE
BIT:[12]
(-5250 2300) 0;
DISPLAY LEFT (-5250 2300);
DISPLAY 1.021277 (-5250 2300);
PAINT PURPLE (-5250 2300);
FORCENOTE
0:24 MHZ
(-4300 2300) 0;
DISPLAY LEFT (-4300 2300);
DISPLAY 0.851064 (-4300 2300);
PAINT PURPLE (-4300 2300);
FORCENOTE
BIT[18]:SELECT USBCKI INPUT FREQUENCY
(-4325 2375) 0;
DISPLAY LEFT (-4325 2375);
DISPLAY 1.191489 (-4325 2375);
PAINT PURPLE (-4325 2375);
FORCENOTE
1:ENABLE BMC 2ND BOOT WATCHDOG TIMER AT POWER UP
(-4325 2500) 0;
DISPLAY LEFT (-4325 2500);
DISPLAY 0.851064 (-4325 2500);
PAINT PURPLE (-4325 2500);
FORCENOTE
0:DISABLE(DEFUALT)
(-4325 2575) 0;
DISPLAY LEFT (-4325 2575);
DISPLAY 1.191489 (-4325 2575);
PAINT PURPLE (-4325 2575);
FORCENOTE
BIT:[6]
(-5225 2525) 0;
DISPLAY LEFT (-5225 2525);
DISPLAY 1.021277 (-5225 2525);
PAINT PURPLE (-5225 2525);
FORCENOTE
BIT:[13]
(-5250 2075) 0;
DISPLAY LEFT (-5250 2075);
DISPLAY 1.021277 (-5250 2075);
PAINT PURPLE (-5250 2075);
FORCENOTE
BIT:[19]
(-5250 1700) 0;
DISPLAY LEFT (-5250 1700);
DISPLAY 1.021277 (-5250 1700);
PAINT PURPLE (-5250 1700);
FORCENOTE
BIT:[24]
(-5600 475) 0;
DISPLAY LEFT (-5600 475);
DISPLAY 1.021277 (-5600 475);
PAINT PURPLE (-5600 475);
FORCENOTE
BOM_COST=SM_MEM
(-7765 271) 0;
DISPLAY LEFT (-7765 271);
DISPLAY 0.765957 (-7765 271);
PAINT PURPLE (-7765 271);
FORCENOTE
BIT[7]: DEFINE MAC\#2 INTERFACE
(-2075 4125) 0;
DISPLAY LEFT (-2075 4125);
DISPLAY 1.191489 (-2075 4125);
PAINT PURPLE (-2075 4125);
FORCENOTE
0:RMII/NCSI(DEFUALT)
(-2075 4050) 0;
DISPLAY LEFT (-2075 4050);
DISPLAY 1.191489 (-2075 4050);
PAINT PURPLE (-2075 4050);
FORCENOTE
0:DECODE 0X2E(DEFAULT)
(-2125 4625) 0;
DISPLAY LEFT (-2125 4625);
DISPLAY 1.191489 (-2125 4625);
PAINT PURPLE (-2125 4625);
FORCENOTE
BIT[22]: ENABLE GPIOD PASS-THROUGH MODE
(-2075 3650) 0;
DISPLAY LEFT (-2075 3650);
DISPLAY 1.191489 (-2075 3650);
PAINT PURPLE (-2075 3650);
FORCENOTE
0:DISABLE(DEFUALT)
(-2050 3575) 0;
DISPLAY LEFT (-2050 3575);
DISPLAY 1.191489 (-2050 3575);
PAINT PURPLE (-2050 3575);
FORCENOTE
BIT[23]: SELECT 25 MHZ REFERENCE CLOCK INPUT MODE
(-2050 3300) 0;
DISPLAY LEFT (-2050 3300);
DISPLAY 1.191489 (-2050 3300);
PAINT PURPLE (-2050 3300);
FORCENOTE
0:CLKIN 24MHZ  AND USBCKI NOT USED(DEFAULT)
(-2050 3200) 0;
DISPLAY LEFT (-2050 3200);
DISPLAY 1.191489 (-2050 3200);
PAINT PURPLE (-2050 3200);
FORCENOTE
1:CLKIN 25MHZ  AND USNCKI =24/48 MHZ
(-2050 3125) 0;
DISPLAY LEFT (-2050 3125);
DISPLAY 1.021277 (-2050 3125);
PAINT PURPLE (-2050 3125);
FORCENOTE
BIT[24]: SELECT DDR4 SDRAM
(-2050 3000) 0;
DISPLAY LEFT (-2050 3000);
DISPLAY 1.191489 (-2050 3000);
PAINT PURPLE (-2050 3000);
FORCENOTE
1:DDR4 SDRAM(DEFUALT)
(-2075 2825) 0;
DISPLAY LEFT (-2075 2825);
DISPLAY 1.191489 (-2075 2825);
PAINT PURPLE (-2075 2825);
FORCENOTE
BIT[29]: SELECT UART DEBUG PORT
(-2075 2675) 0;
DISPLAY LEFT (-2075 2675);
DISPLAY 1.191489 (-2075 2675);
PAINT PURPLE (-2075 2675);
FORCENOTE
0:SELECT UART1 (DEFUALT)
(-2075 2575) 0;
DISPLAY LEFT (-2075 2575);
DISPLAY 1.191489 (-2075 2575);
PAINT PURPLE (-2075 2575);
FORCENOTE
0:DISABLE(DEFUALT)
(-2075 3825) 0;
DISPLAY LEFT (-2075 3825);
DISPLAY 1.191489 (-2075 3825);
PAINT PURPLE (-2075 3825);
FORCENOTE
BIT[21]: ENABLE GPIOE PASS-THROUGH MODE
(-2100 3900) 0;
DISPLAY LEFT (-2100 3900);
DISPLAY 1.191489 (-2100 3900);
PAINT PURPLE (-2100 3900);
FORCENOTE
BIT[16]: SUPERIO CONFIGURATION ADDRESS SELECTION
(-2125 4700) 0;
DISPLAY LEFT (-2125 4700);
DISPLAY 1.191489 (-2125 4700);
PAINT PURPLE (-2125 4700);
FORCENOTE
BIT[19]: ENABLE ACPI FUNCTION
(-2125 4375) 0;
DISPLAY LEFT (-2125 4375);
DISPLAY 1.191489 (-2125 4375);
PAINT PURPLE (-2125 4375);
FORCENOTE
0:DISABLE
(-2125 4325) 0;
DISPLAY LEFT (-2125 4325);
DISPLAY 1.021277 (-2125 4325);
PAINT PURPLE (-2125 4325);
FORCENOTE
1:DECODE 0X4E
(-2125 4525) 0;
DISPLAY LEFT (-2125 4525);
DISPLAY 1.021277 (-2125 4525);
PAINT PURPLE (-2125 4525);
FORCENOTE
1:RGMII
(-2075 3975) 0;
DISPLAY LEFT (-2075 3975);
DISPLAY 1.021277 (-2075 3975);
PAINT PURPLE (-2075 3975);
FORCENOTE
1:ENABLE(DEFAULT)
(-2125 4250) 0;
DISPLAY LEFT (-2125 4250);
DISPLAY 1.191489 (-2125 4250);
PAINT PURPLE (-2125 4250);
FORCENOTE
1:ENABLE
(-2075 3750) 0;
DISPLAY LEFT (-2075 3750);
DISPLAY 1.021277 (-2075 3750);
PAINT PURPLE (-2075 3750);
FORCENOTE
1:ENABLE BOOT (DEFUALT)
(-4375 4575) 0;
DISPLAY LEFT (-4375 4575);
DISPLAY 1.191489 (-4375 4575);
PAINT PURPLE (-4375 4575);
FORCENOTE
0:DISABLE CPU OPERATION, WHEN NO FIRMWARE EXIST
(-4350 4500) 0;
DISPLAY LEFT (-4350 4500);
DISPLAY 0.851064 (-4350 4500);
PAINT PURPLE (-4350 4500);
FORCENOTE
1:ENABLE SPI FLASH STRAP AUTO FETCH(DEFUALT)
(-4350 4050) 0;
DISPLAY LEFT (-4350 4050);
DISPLAY 1.191489 (-4350 4050);
PAINT PURPLE (-4350 4050);
FORCENOTE
1:ENABLE GPIO STRAP MODE(DEFUALT)
(-4375 4275) 0;
DISPLAY LEFT (-4375 4275);
DISPLAY 1.191489 (-4375 4275);
PAINT PURPLE (-4375 4275);
FORCENOTE
0:DISABLE SPI FLASH STRAP AUTO FETCH
(-4325 3975) 0;
DISPLAY LEFT (-4325 3975);
DISPLAY 0.851064 (-4325 3975);
PAINT PURPLE (-4325 3975);
FORCENOTE
BIT[3:2]: VGA MEMORY SIZE
(-4325 3650) 0;
DISPLAY LEFT (-4325 3650);
DISPLAY 1.191489 (-4325 3650);
PAINT PURPLE (-4325 3650);
FORCENOTE
BIT[0]:
(-4375 4675) 0;
DISPLAY LEFT (-4375 4675);
DISPLAY 1.191489 (-4375 4675);
PAINT PURPLE (-4375 4675);
FORCENOTE
00: 8MB
(-4325 3600) 0;
DISPLAY LEFT (-4325 3600);
DISPLAY 0.851064 (-4325 3600);
PAINT PURPLE (-4325 3600);
FORCENOTE
BMC STRAPPING
(-4375 4775) 0;
DISPLAY LEFT (-4375 4775);
DISPLAY 1.702128 (-4375 4775);
PAINT PURPLE (-4375 4775);
FORCENOTE
BIT[30]:
(-4350 4375) 0;
DISPLAY LEFT (-4350 4375);
DISPLAY 1.191489 (-4350 4375);
PAINT PURPLE (-4350 4375);
FORCENOTE
BIT[31]:
(-4350 4125) 0;
DISPLAY LEFT (-4350 4125);
DISPLAY 1.021277 (-4350 4125);
PAINT PURPLE (-4350 4125);
FORCENOTE
0:DISABLE GPIO STRAP MODE
(-4350 4225) 0;
DISPLAY LEFT (-4350 4225);
DISPLAY 0.851064 (-4350 4225);
PAINT PURPLE (-4350 4225);
FORCENOTE
BIT[25]:
(-4350 3875) 0;
DISPLAY LEFT (-4350 3875);
DISPLAY 1.191489 (-4350 3875);
PAINT PURPLE (-4350 3875);
FORCENOTE
1:ESPI MODE
(-4325 3825) 0;
DISPLAY LEFT (-4325 3825);
DISPLAY 0.851064 (-4325 3825);
PAINT PURPLE (-4325 3825);
FORCENOTE
0:LPC MODE(DEFUALT)
(-4325 3750) 0;
DISPLAY LEFT (-4325 3750);
DISPLAY 1.191489 (-4325 3750);
PAINT PURPLE (-4325 3750);
FORCENOTE
BIT:[3]
(-5175 4000) 0;
DISPLAY LEFT (-5175 4000);
DISPLAY 1.021277 (-5175 4000);
PAINT PURPLE (-5175 4000);
FORCENOTE
BIT:[30]
(-5150 4550) 0;
DISPLAY LEFT (-5150 4550);
DISPLAY 1.021277 (-5150 4550);
PAINT PURPLE (-5150 4550);
FORCENOTE
BIT:[0]
(-5150 4650) 0;
DISPLAY LEFT (-5150 4650);
DISPLAY 1.021277 (-5150 4650);
PAINT PURPLE (-5150 4650);
FORCENOTE
BIT:[31]
(-5150 4425) 0;
DISPLAY LEFT (-5150 4425);
DISPLAY 1.021277 (-5150 4425);
PAINT PURPLE (-5150 4425);
FORCENOTE
BIT:[25]
(-5150 4275) 0;
DISPLAY LEFT (-5150 4275);
DISPLAY 1.021277 (-5150 4275);
PAINT PURPLE (-5150 4275);
FORCENOTE
1:SELECT UART5
(-2075 2500) 0;
DISPLAY LEFT (-2075 2500);
DISPLAY 1.021277 (-2075 2500);
PAINT PURPLE (-2075 2500);
FORCENOTE
0:DDR3 SDRAM
(-2050 2925) 0;
DISPLAY LEFT (-2050 2925);
DISPLAY 1.021277 (-2050 2925);
PAINT PURPLE (-2050 2925);
FORCENOTE
1:ENABLE
(-2050 3500) 0;
DISPLAY LEFT (-2050 3500);
DISPLAY 1.021277 (-2050 3500);
PAINT PURPLE (-2050 3500);
FORCENOTE
1:ESPI RESPOND WITH FLASH ATTACHED
(-4325 1350) 0;
DISPLAY LEFT (-4325 1350);
DISPLAY 0.851064 (-4325 1350);
PAINT PURPLE (-4325 1350);
FORCENOTE
0:ESPI RESPOND WITH NO FLASH ATTACHED(DEFUALT)
(-4325 1425) 0;
DISPLAY LEFT (-4325 1425);
DISPLAY 1.191489 (-4325 1425);
PAINT PURPLE (-4325 1425);
FORCENOTE
BIT[6]: DEFINE MAC\#1 INTERFACE
(-4325 1250) 0;
DISPLAY LEFT (-4325 1250);
DISPLAY 1.191489 (-4325 1250);
PAINT PURPLE (-4325 1250);
FORCENOTE
10:RESERVED,ENABLE SPI MASTER AND SPI SLAVE TO AHB BRIDGE
(-4325 800) 0;
DISPLAY LEFT (-4325 800);
DISPLAY 0.851064 (-4325 800);
PAINT PURPLE (-4325 800);
FORCENOTE
01:ENABLE SPI MASTER(DEFAULT)
(-4325 850) 0;
DISPLAY LEFT (-4325 850);
DISPLAY 1.191489 (-4325 850);
PAINT PURPLE (-4325 850);
FORCENOTE
BIT[13:12]: SPI MODE SELECTION
(-4325 1000) 0;
DISPLAY LEFT (-4325 1000);
DISPLAY 1.191489 (-4325 1000);
PAINT PURPLE (-4325 1000);
FORCENOTE
1:SELECT THE CLASS CODE FOR VGA DEVICE(DEFUALT)
(-4325 2800) 0;
DISPLAY LEFT (-4325 2800);
DISPLAY 1.191489 (-4325 2800);
PAINT PURPLE (-4325 2800);
FORCENOTE
0:SELECT THE CLASS CODE FOR VIDEO DEVICE
(-4325 2900) 0;
DISPLAY LEFT (-4325 2900);
DISPLAY 0.851064 (-4325 2900);
PAINT PURPLE (-4325 2900);
FORCENOTE
BIT[15]: VGA CLASS CODE SELECTION
(-4325 3000) 0;
DISPLAY LEFT (-4325 3000);
DISPLAY 1.021277 (-4325 3000);
PAINT PURPLE (-4325 3000);
FORCENOTE
BIT[5]: ENABLE VGA BIOS ROM
(-4325 3250) 0;
DISPLAY LEFT (-4325 3250);
DISPLAY 1.191489 (-4325 3250);
PAINT PURPLE (-4325 3250);
FORCENOTE
BIT[17]:ENABLE BMC 2ND BOOT WATCHDOG TIMER
(-4325 2675) 0;
DISPLAY LEFT (-4325 2675);
DISPLAY 1.021277 (-4325 2675);
PAINT PURPLE (-4325 2675);
FORCENOTE
01:16MB(DEFUALT)
(-4325 3450) 0;
DISPLAY LEFT (-4325 3450);
DISPLAY 1.191489 (-4325 3450);
PAINT PURPLE (-4325 3450);
FORCENOTE
11:64MB
(-4325 3375) 0;
DISPLAY LEFT (-4325 3375);
DISPLAY 0.851064 (-4325 3375);
PAINT PURPLE (-4325 3375);
FORCENOTE
10:32MB
(-4325 3525) 0;
DISPLAY LEFT (-4325 3525);
DISPLAY 0.851064 (-4325 3525);
PAINT PURPLE (-4325 3525);
FORCENOTE
1:RGMII
(-4325 1100) 0;
DISPLAY LEFT (-4325 1100);
DISPLAY 0.851064 (-4325 1100);
PAINT PURPLE (-4325 1100);
FORCENOTE
0:RMII/NCSI(DEFUALT)
(-4325 1150) 0;
DISPLAY LEFT (-4325 1150);
DISPLAY 1.191489 (-4325 1150);
PAINT PURPLE (-4325 1150);
FORCENOTE
00: DISABLE SPI INTERFACE
(-4325 925) 0;
DISPLAY LEFT (-4325 925);
DISPLAY 0.851064 (-4325 925);
PAINT PURPLE (-4325 925);
FORCENOTE
11:ENABLE SPI PASS-THROUGH
(-4325 725) 0;
DISPLAY LEFT (-4325 725);
DISPLAY 0.851064 (-4325 725);
PAINT PURPLE (-4325 725);
FORCENOTE
BIT:[5]
(-5250 3825) 0;
DISPLAY LEFT (-5250 3825);
DISPLAY 1.021277 (-5250 3825);
PAINT PURPLE (-5250 3825);
FORCENOTE
BIT:[23]
(-5600 700) 0;
DISPLAY LEFT (-5600 700);
DISPLAY 1.021277 (-5600 700);
PAINT PURPLE (-5600 700);
FORCENOTE
BIT:[29]
(-5600 225) 0;
DISPLAY LEFT (-5600 225);
DISPLAY 1.021277 (-5600 225);
PAINT PURPLE (-5600 225);
FORCENOTE
BIT:[21]
(-5300 1150) 0;
DISPLAY LEFT (-5300 1150);
DISPLAY 1.021277 (-5300 1150);
PAINT PURPLE (-5300 1150);
FORCENOTE
BIT:[20]
(-5225 3175) 0;
DISPLAY LEFT (-5225 3175);
DISPLAY 1.021277 (-5225 3175);
PAINT PURPLE (-5225 3175);
FORCENOTE
BIT:[18]
(-5250 3300) 0;
DISPLAY LEFT (-5250 3300);
DISPLAY 1.021277 (-5250 3300);
PAINT PURPLE (-5250 3300);
FORCENOTE
BIT:[7]
(-5250 1400) 0;
DISPLAY LEFT (-5250 1400);
DISPLAY 1.021277 (-5250 1400);
PAINT PURPLE (-5250 1400);
FORCENOTE
BIT:[15]
(-5250 3625) 0;
DISPLAY LEFT (-5250 3625);
DISPLAY 1.021277 (-5250 3625);
PAINT PURPLE (-5250 3625);
FORCENOTE
BIT:[17]
(-5250 3450) 0;
DISPLAY LEFT (-5250 3450);
DISPLAY 1.021277 (-5250 3450);
PAINT PURPLE (-5250 3450);
FORCENOTE
BIT:[22]
(-5625 925) 0;
DISPLAY LEFT (-5625 925);
DISPLAY 1.021277 (-5625 925);
PAINT PURPLE (-5625 925);
FORCENOTE
1:48MHZ(DEFUALT)
(-4325 2225) 0;
DISPLAY LEFT (-4325 2225);
DISPLAY 1.191489 (-4325 2225);
PAINT PURPLE (-4325 2225);
FORCENOTE
BIT[20]:DISABLE LPC TO DECODE SUPERIO 0X2E/0X4E ADDRESS
(-4325 2100) 0;
DISPLAY LEFT (-4325 2100);
DISPLAY 1.191489 (-4325 2100);
PAINT PURPLE (-4325 2100);
FORCENOTE
0:ENABLE ADRESS DECODING  (DEFUALT)
(-4325 2000) 0;
DISPLAY LEFT (-4325 2000);
DISPLAY 1.191489 (-4325 2000);
PAINT PURPLE (-4325 2000);
FORCENOTE
1:DISABLE ADRESS DECODING
(-4325 1925) 0;
DISPLAY LEFT (-4325 1925);
DISPLAY 0.851064 (-4325 1925);
PAINT PURPLE (-4325 1925);
FORCENOTE
BIT[27]:ENABLE FAST RESET MODE FOR ARM ICE DEBUGGER
(-4325 1800) 0;
DISPLAY LEFT (-4325 1800);
DISPLAY 1.191489 (-4325 1800);
PAINT PURPLE (-4325 1800);
FORCENOTE
0:LONG RESET MODE,NORMAL OPERATION(DEFUALT)
(-4325 1725) 0;
DISPLAY LEFT (-4325 1725);
DISPLAY 1.191489 (-4325 1725);
PAINT PURPLE (-4325 1725);
FORCENOTE
1:FAST RESET MODE,FOR ICE DEBUGGER CONNECTION
(-4325 1650) 0;
DISPLAY LEFT (-4325 1650);
DISPLAY 0.851064 (-4325 1650);
PAINT PURPLE (-4325 1650);
FORCENOTE
BIT[26]:ENABLE ESPI FLASH MODE
(-4325 1525) 0;
DISPLAY LEFT (-4325 1525);
DISPLAY 1.191489 (-4325 1525);
PAINT PURPLE (-4325 1525);
FORCENOTE
1:ENABLE DEDICATED VGA BIOS ROM
(-4325 3100) 0;
DISPLAY LEFT (-4325 3100);
DISPLAY 0.851064 (-4325 3100);
PAINT PURPLE (-4325 3100);
FORCENOTE
0:NO VGA BIOS,MERGED IN SYSTEM BIOS(DEFUALT)
(-4325 3150) 0;
DISPLAY LEFT (-4325 3150);
DISPLAY 1.191489 (-4325 3150);
PAINT PURPLE (-4325 3150);
FORCENOTE
BIT:[16]
(-5250 1875) 0;
DISPLAY LEFT (-5250 1875);
DISPLAY 1.021277 (-5250 1875);
PAINT PURPLE (-5250 1875);
FORCENOTE
BIT:[26]
(-5250 2725) 0;
DISPLAY LEFT (-5250 2725);
DISPLAY 1.021277 (-5250 2725);
PAINT PURPLE (-5250 2725);
FORCENOTE
BIT:[27]
(-5250 2925) 0;
DISPLAY LEFT (-5250 2925);
DISPLAY 1.021277 (-5250 2925);
PAINT PURPLE (-5250 2925);
QUIT
